FILE_TYPE = MACRO_DRAWING;
SET COLOR_WIRE YELLOW;
SET COLOR_PROP ORANGE;
SET COLOR_DOT WHITE;
SET COLOR_ARC YELLOW;
SET COLOR_BODY GREEN;
SET COLOR_NOTE PURPLE;
SET PROP_DISPLAY VALUE;
SET PAGE_NUMBER P32;
FORCEADD GENOA_SP5..34
(-7775 3450);
FORCEPROP 1 LAST LOCATION U25
J 0
(-8175 6600);
DISPLAY 0.489362 (-8175 6600);
PAINT SKYBLUE (-8175 6600);
FORCEPROP 0 LAST $SEC 34
J 0
(-8150 6850);
DISPLAY 0.680851 (-8150 6850);
PAINT MONO (-8150 6850);
DISPLAY INVISIBLE (-8150 6850);
FORCEPROP 0 LAST CDS_SEC 34
J 0
(-8175 6725);
DISPLAY 1.021277 (-8175 6725);
DISPLAY INVISIBLE (-8175 6725);
FORCEPROP 0 LASTPIN (-8325 6400) $PN BL26
J 2
(-8335 6410);
DISPLAY 0.489362 (-8335 6410);
PAINT MONO (-8335 6410);
FORCEPROP 0 LASTPIN (-8325 6350) $PN BL28
J 2
(-8335 6360);
DISPLAY 0.489362 (-8335 6360);
PAINT MONO (-8335 6360);
FORCEPROP 0 LASTPIN (-8325 6300) $PN BL49
J 2
(-8335 6310);
DISPLAY 0.489362 (-8335 6310);
PAINT MONO (-8335 6310);
FORCEPROP 0 LASTPIN (-8325 6250) $PN BL51
J 2
(-8335 6260);
DISPLAY 0.489362 (-8335 6260);
PAINT MONO (-8335 6260);
FORCEPROP 0 LASTPIN (-8325 6200) $PN BL53
J 2
(-8335 6210);
DISPLAY 0.489362 (-8335 6210);
PAINT MONO (-8335 6210);
FORCEPROP 0 LASTPIN (-8325 6150) $PN BL56
J 2
(-8335 6160);
DISPLAY 0.489362 (-8335 6160);
PAINT MONO (-8335 6160);
FORCEPROP 0 LASTPIN (-8325 6100) $PN BL58
J 2
(-8335 6110);
DISPLAY 0.489362 (-8335 6110);
PAINT MONO (-8335 6110);
FORCEPROP 0 LASTPIN (-8325 6050) $PN BL61
J 2
(-8335 6060);
DISPLAY 0.489362 (-8335 6060);
PAINT MONO (-8335 6060);
FORCEPROP 0 LASTPIN (-8325 6000) $PN BL63
J 2
(-8335 6010);
DISPLAY 0.489362 (-8335 6010);
PAINT MONO (-8335 6010);
FORCEPROP 0 LASTPIN (-8325 5950) $PN BL65
J 2
(-8335 5960);
DISPLAY 0.489362 (-8335 5960);
PAINT MONO (-8335 5960);
FORCEPROP 0 LASTPIN (-8325 5900) $PN BL68
J 2
(-8335 5910);
DISPLAY 0.489362 (-8335 5910);
PAINT MONO (-8335 5910);
FORCEPROP 0 LASTPIN (-8325 5850) $PN BL70
J 2
(-8335 5860);
DISPLAY 0.489362 (-8335 5860);
PAINT MONO (-8335 5860);
FORCEPROP 0 LASTPIN (-8325 5800) $PN BL72
J 2
(-8335 5810);
DISPLAY 0.489362 (-8335 5810);
PAINT MONO (-8335 5810);
FORCEPROP 0 LASTPIN (-8325 5750) $PN BL75
J 2
(-8335 5760);
DISPLAY 0.489362 (-8335 5760);
PAINT MONO (-8335 5760);
FORCEPROP 0 LASTPIN (-8325 5700) $PN BM3
J 2
(-8335 5710);
DISPLAY 0.489362 (-8335 5710);
PAINT MONO (-8335 5710);
FORCEPROP 0 LASTPIN (-8325 5650) $PN BM8
J 2
(-8335 5660);
DISPLAY 0.489362 (-8335 5660);
PAINT MONO (-8335 5660);
FORCEPROP 0 LASTPIN (-8325 5600) $PN BM10
J 2
(-8335 5610);
DISPLAY 0.489362 (-8335 5610);
PAINT MONO (-8335 5610);
FORCEPROP 0 LASTPIN (-8325 5550) $PN BM15
J 2
(-8335 5560);
DISPLAY 0.489362 (-8335 5560);
PAINT MONO (-8335 5560);
FORCEPROP 0 LASTPIN (-8325 5500) $PN BM17
J 2
(-8335 5510);
DISPLAY 0.489362 (-8335 5510);
PAINT MONO (-8335 5510);
FORCEPROP 0 LASTPIN (-8325 5450) $PN BM23
J 2
(-8335 5460);
DISPLAY 0.489362 (-8335 5460);
PAINT MONO (-8335 5460);
FORCEPROP 0 LASTPIN (-8325 5400) $PN BM25
J 2
(-8335 5410);
DISPLAY 0.489362 (-8335 5410);
PAINT MONO (-8335 5410);
FORCEPROP 0 LASTPIN (-8325 5350) $PN BM27
J 2
(-8335 5360);
DISPLAY 0.489362 (-8335 5360);
PAINT MONO (-8335 5360);
FORCEPROP 0 LASTPIN (-8325 5300) $PN BM29
J 2
(-8335 5310);
DISPLAY 0.489362 (-8335 5310);
PAINT MONO (-8335 5310);
FORCEPROP 0 LASTPIN (-8325 5250) $PN BM31
J 2
(-8335 5260);
DISPLAY 0.489362 (-8335 5260);
PAINT MONO (-8335 5260);
FORCEPROP 0 LASTPIN (-8325 5200) $PN BM33
J 2
(-8335 5210);
DISPLAY 0.489362 (-8335 5210);
PAINT MONO (-8335 5210);
FORCEPROP 0 LASTPIN (-8325 5150) $PN BM35
J 2
(-8335 5160);
DISPLAY 0.489362 (-8335 5160);
PAINT MONO (-8335 5160);
FORCEPROP 0 LASTPIN (-8325 5100) $PN BM37
J 2
(-8335 5110);
DISPLAY 0.489362 (-8335 5110);
PAINT MONO (-8335 5110);
FORCEPROP 0 LASTPIN (-8325 5050) $PN BM40
J 2
(-8335 5060);
DISPLAY 0.489362 (-8335 5060);
PAINT MONO (-8335 5060);
FORCEPROP 0 LASTPIN (-8325 5000) $PN BM42
J 2
(-8335 5010);
DISPLAY 0.489362 (-8335 5010);
PAINT MONO (-8335 5010);
FORCEPROP 0 LASTPIN (-8325 4950) $PN BM44
J 2
(-8335 4960);
DISPLAY 0.489362 (-8335 4960);
PAINT MONO (-8335 4960);
FORCEPROP 0 LASTPIN (-8325 4900) $PN BM46
J 2
(-8335 4910);
DISPLAY 0.489362 (-8335 4910);
PAINT MONO (-8335 4910);
FORCEPROP 0 LASTPIN (-8325 4850) $PN BM48
J 2
(-8335 4860);
DISPLAY 0.489362 (-8335 4860);
PAINT MONO (-8335 4860);
FORCEPROP 0 LASTPIN (-8325 4800) $PN BM50
J 2
(-8335 4810);
DISPLAY 0.489362 (-8335 4810);
PAINT MONO (-8335 4810);
FORCEPROP 0 LASTPIN (-8325 4750) $PN BM52
J 2
(-8335 4760);
DISPLAY 0.489362 (-8335 4760);
PAINT MONO (-8335 4760);
FORCEPROP 0 LASTPIN (-8325 4700) $PN BM54
J 2
(-8335 4710);
DISPLAY 0.489362 (-8335 4710);
PAINT MONO (-8335 4710);
FORCEPROP 0 LASTPIN (-8325 4650) $PN BM59
J 2
(-8335 4660);
DISPLAY 0.489362 (-8335 4660);
PAINT MONO (-8335 4660);
FORCEPROP 0 LASTPIN (-8325 4600) $PN BM61
J 2
(-8335 4610);
DISPLAY 0.489362 (-8335 4610);
PAINT MONO (-8335 4610);
FORCEPROP 0 LASTPIN (-8325 4550) $PN BM66
J 2
(-8335 4560);
DISPLAY 0.489362 (-8335 4560);
PAINT MONO (-8335 4560);
FORCEPROP 0 LASTPIN (-8325 4500) $PN BM68
J 2
(-8335 4510);
DISPLAY 0.489362 (-8335 4510);
PAINT MONO (-8335 4510);
FORCEPROP 0 LASTPIN (-8325 4450) $PN BM73
J 2
(-8335 4460);
DISPLAY 0.489362 (-8335 4460);
PAINT MONO (-8335 4460);
FORCEPROP 0 LASTPIN (-8325 4400) $PN BN1
J 2
(-8335 4410);
DISPLAY 0.489362 (-8335 4410);
PAINT MONO (-8335 4410);
FORCEPROP 0 LASTPIN (-8325 4350) $PN BN4
J 2
(-8335 4360);
DISPLAY 0.489362 (-8335 4360);
PAINT MONO (-8335 4360);
FORCEPROP 0 LASTPIN (-8325 4300) $PN BN6
J 2
(-8335 4310);
DISPLAY 0.489362 (-8335 4310);
PAINT MONO (-8335 4310);
FORCEPROP 0 LASTPIN (-8325 4250) $PN BN8
J 2
(-8335 4260);
DISPLAY 0.489362 (-8335 4260);
PAINT MONO (-8335 4260);
FORCEPROP 0 LASTPIN (-8325 4200) $PN BN11
J 2
(-8335 4210);
DISPLAY 0.489362 (-8335 4210);
PAINT MONO (-8335 4210);
FORCEPROP 0 LASTPIN (-8325 4150) $PN BN13
J 2
(-8335 4160);
DISPLAY 0.489362 (-8335 4160);
PAINT MONO (-8335 4160);
FORCEPROP 0 LASTPIN (-8325 4100) $PN BN15
J 2
(-8335 4110);
DISPLAY 0.489362 (-8335 4110);
PAINT MONO (-8335 4110);
FORCEPROP 0 LASTPIN (-8325 4050) $PN BN18
J 2
(-8335 4060);
DISPLAY 0.489362 (-8335 4060);
PAINT MONO (-8335 4060);
FORCEPROP 0 LASTPIN (-8325 4000) $PN BN20
J 2
(-8335 4010);
DISPLAY 0.489362 (-8335 4010);
PAINT MONO (-8335 4010);
FORCEPROP 0 LASTPIN (-8325 3950) $PN BN22
J 2
(-8335 3960);
DISPLAY 0.489362 (-8335 3960);
PAINT MONO (-8335 3960);
FORCEPROP 0 LASTPIN (-8325 3900) $PN BN24
J 2
(-8335 3910);
DISPLAY 0.489362 (-8335 3910);
PAINT MONO (-8335 3910);
FORCEPROP 0 LASTPIN (-8325 3850) $PN BN26
J 2
(-8335 3860);
DISPLAY 0.489362 (-8335 3860);
PAINT MONO (-8335 3860);
FORCEPROP 0 LASTPIN (-8325 3800) $PN BN28
J 2
(-8335 3810);
DISPLAY 0.489362 (-8335 3810);
PAINT MONO (-8335 3810);
FORCEPROP 0 LASTPIN (-8325 3750) $PN BN30
J 2
(-8335 3760);
DISPLAY 0.489362 (-8335 3760);
PAINT MONO (-8335 3760);
FORCEPROP 0 LASTPIN (-8325 3700) $PN BN32
J 2
(-8335 3710);
DISPLAY 0.489362 (-8335 3710);
PAINT MONO (-8335 3710);
FORCEPROP 0 LASTPIN (-8325 3650) $PN BN34
J 2
(-8335 3660);
DISPLAY 0.489362 (-8335 3660);
PAINT MONO (-8335 3660);
FORCEPROP 0 LASTPIN (-8325 3600) $PN BN36
J 2
(-8335 3610);
DISPLAY 0.489362 (-8335 3610);
PAINT MONO (-8335 3610);
FORCEPROP 0 LASTPIN (-8325 3550) $PN BN41
J 2
(-8335 3560);
DISPLAY 0.489362 (-8335 3560);
PAINT MONO (-8335 3560);
FORCEPROP 0 LASTPIN (-8325 3500) $PN BN43
J 2
(-8335 3510);
DISPLAY 0.489362 (-8335 3510);
PAINT MONO (-8335 3510);
FORCEPROP 0 LASTPIN (-8325 3450) $PN BN45
J 2
(-8335 3460);
DISPLAY 0.489362 (-8335 3460);
PAINT MONO (-8335 3460);
FORCEPROP 0 LASTPIN (-8325 3400) $PN BN47
J 2
(-8335 3410);
DISPLAY 0.489362 (-8335 3410);
PAINT MONO (-8335 3410);
FORCEPROP 0 LASTPIN (-8325 3350) $PN BN49
J 2
(-8335 3360);
DISPLAY 0.489362 (-8335 3360);
PAINT MONO (-8335 3360);
FORCEPROP 0 LASTPIN (-8325 3300) $PN BN51
J 2
(-8335 3310);
DISPLAY 0.489362 (-8335 3310);
PAINT MONO (-8335 3310);
FORCEPROP 0 LASTPIN (-8325 3250) $PN BN53
J 2
(-8335 3260);
DISPLAY 0.489362 (-8335 3260);
PAINT MONO (-8335 3260);
FORCEPROP 0 LASTPIN (-8325 3200) $PN BN56
J 2
(-8335 3210);
DISPLAY 0.489362 (-8335 3210);
PAINT MONO (-8335 3210);
FORCEPROP 0 LASTPIN (-8325 3150) $PN BN58
J 2
(-8335 3160);
DISPLAY 0.489362 (-8335 3160);
PAINT MONO (-8335 3160);
FORCEPROP 0 LASTPIN (-8325 3100) $PN BN61
J 2
(-8335 3110);
DISPLAY 0.489362 (-8335 3110);
PAINT MONO (-8335 3110);
FORCEPROP 0 LASTPIN (-8325 3050) $PN BN63
J 2
(-8335 3060);
DISPLAY 0.489362 (-8335 3060);
PAINT MONO (-8335 3060);
FORCEPROP 0 LASTPIN (-8325 3000) $PN BN65
J 2
(-8335 3010);
DISPLAY 0.489362 (-8335 3010);
PAINT MONO (-8335 3010);
FORCEPROP 0 LASTPIN (-8325 2950) $PN BN68
J 2
(-8335 2960);
DISPLAY 0.489362 (-8335 2960);
PAINT MONO (-8335 2960);
FORCEPROP 0 LASTPIN (-8325 2900) $PN BN70
J 2
(-8335 2910);
DISPLAY 0.489362 (-8335 2910);
PAINT MONO (-8335 2910);
FORCEPROP 0 LASTPIN (-8325 2850) $PN BN72
J 2
(-8335 2860);
DISPLAY 0.489362 (-8335 2860);
PAINT MONO (-8335 2860);
FORCEPROP 0 LASTPIN (-8325 2800) $PN BN75
J 2
(-8335 2810);
DISPLAY 0.489362 (-8335 2810);
PAINT MONO (-8335 2810);
FORCEPROP 0 LASTPIN (-8325 2750) $PN BP3
J 2
(-8335 2760);
DISPLAY 0.489362 (-8335 2760);
PAINT MONO (-8335 2760);
FORCEPROP 0 LASTPIN (-8325 2700) $PN BP5
J 2
(-8335 2710);
DISPLAY 0.489362 (-8335 2710);
PAINT MONO (-8335 2710);
FORCEPROP 0 LASTPIN (-8325 2650) $PN BP8
J 2
(-8335 2660);
DISPLAY 0.489362 (-8335 2660);
PAINT MONO (-8335 2660);
FORCEPROP 0 LASTPIN (-8325 2600) $PN BP10
J 2
(-8335 2610);
DISPLAY 0.489362 (-8335 2610);
PAINT MONO (-8335 2610);
FORCEPROP 0 LASTPIN (-8325 2550) $PN BP12
J 2
(-8335 2560);
DISPLAY 0.489362 (-8335 2560);
PAINT MONO (-8335 2560);
FORCEPROP 0 LASTPIN (-8325 2500) $PN BP15
J 2
(-8335 2510);
DISPLAY 0.489362 (-8335 2510);
PAINT MONO (-8335 2510);
FORCEPROP 0 LASTPIN (-8325 2450) $PN BP17
J 2
(-8335 2460);
DISPLAY 0.489362 (-8335 2460);
PAINT MONO (-8335 2460);
FORCEPROP 0 LASTPIN (-8325 2400) $PN BP19
J 2
(-8335 2410);
DISPLAY 0.489362 (-8335 2410);
PAINT MONO (-8335 2410);
FORCEPROP 0 LASTPIN (-8325 2350) $PN BP23
J 2
(-8335 2360);
DISPLAY 0.489362 (-8335 2360);
PAINT MONO (-8335 2360);
FORCEPROP 0 LASTPIN (-8325 2300) $PN BP25
J 2
(-8335 2310);
DISPLAY 0.489362 (-8335 2310);
PAINT MONO (-8335 2310);
FORCEPROP 0 LASTPIN (-8325 2250) $PN BP27
J 2
(-8335 2260);
DISPLAY 0.489362 (-8335 2260);
PAINT MONO (-8335 2260);
FORCEPROP 0 LASTPIN (-8325 2200) $PN BP29
J 2
(-8335 2210);
DISPLAY 0.489362 (-8335 2210);
PAINT MONO (-8335 2210);
FORCEPROP 0 LASTPIN (-8325 2150) $PN BP31
J 2
(-8335 2160);
DISPLAY 0.489362 (-8335 2160);
PAINT MONO (-8335 2160);
FORCEPROP 0 LASTPIN (-8325 2100) $PN BP33
J 2
(-8335 2110);
DISPLAY 0.489362 (-8335 2110);
PAINT MONO (-8335 2110);
FORCEPROP 0 LASTPIN (-8325 2050) $PN BP35
J 2
(-8335 2060);
DISPLAY 0.489362 (-8335 2060);
PAINT MONO (-8335 2060);
FORCEPROP 0 LASTPIN (-8325 2000) $PN BP37
J 2
(-8335 2010);
DISPLAY 0.489362 (-8335 2010);
PAINT MONO (-8335 2010);
FORCEPROP 0 LASTPIN (-8325 1950) $PN BP40
J 2
(-8335 1960);
DISPLAY 0.489362 (-8335 1960);
PAINT MONO (-8335 1960);
FORCEPROP 0 LASTPIN (-8325 1900) $PN BP42
J 2
(-8335 1910);
DISPLAY 0.489362 (-8335 1910);
PAINT MONO (-8335 1910);
FORCEPROP 0 LASTPIN (-8325 1850) $PN BP44
J 2
(-8335 1860);
DISPLAY 0.489362 (-8335 1860);
PAINT MONO (-8335 1860);
FORCEPROP 0 LASTPIN (-8325 1800) $PN BP46
J 2
(-8335 1810);
DISPLAY 0.489362 (-8335 1810);
PAINT MONO (-8335 1810);
FORCEPROP 0 LASTPIN (-8325 1750) $PN BP48
J 2
(-8335 1760);
DISPLAY 0.489362 (-8335 1760);
PAINT MONO (-8335 1760);
FORCEPROP 0 LASTPIN (-8325 1700) $PN BP50
J 2
(-8335 1710);
DISPLAY 0.489362 (-8335 1710);
PAINT MONO (-8335 1710);
FORCEPROP 0 LASTPIN (-8325 1650) $PN BP52
J 2
(-8335 1660);
DISPLAY 0.489362 (-8335 1660);
PAINT MONO (-8335 1660);
FORCEPROP 0 LASTPIN (-8325 1600) $PN BP54
J 2
(-8335 1610);
DISPLAY 0.489362 (-8335 1610);
PAINT MONO (-8335 1610);
FORCEPROP 0 LASTPIN (-8325 1550) $PN BP57
J 2
(-8335 1560);
DISPLAY 0.489362 (-8335 1560);
PAINT MONO (-8335 1560);
FORCEPROP 0 LASTPIN (-8325 1500) $PN BP59
J 2
(-8335 1510);
DISPLAY 0.489362 (-8335 1510);
PAINT MONO (-8335 1510);
FORCEPROP 0 LASTPIN (-8325 1450) $PN BP61
J 2
(-8335 1460);
DISPLAY 0.489362 (-8335 1460);
PAINT MONO (-8335 1460);
FORCEPROP 0 LASTPIN (-8325 1400) $PN BP64
J 2
(-8335 1410);
DISPLAY 0.489362 (-8335 1410);
PAINT MONO (-8335 1410);
FORCEPROP 0 LASTPIN (-8325 1350) $PN BP66
J 2
(-8335 1360);
DISPLAY 0.489362 (-8335 1360);
PAINT MONO (-8335 1360);
FORCEPROP 0 LASTPIN (-8325 1300) $PN BP68
J 2
(-8335 1310);
DISPLAY 0.489362 (-8335 1310);
PAINT MONO (-8335 1310);
FORCEPROP 0 LASTPIN (-8325 1250) $PN BP71
J 2
(-8335 1260);
DISPLAY 0.489362 (-8335 1260);
PAINT MONO (-8335 1260);
FORCEPROP 0 LASTPIN (-8325 1200) $PN BP73
J 2
(-8335 1210);
DISPLAY 0.489362 (-8335 1210);
PAINT MONO (-8335 1210);
FORCEPROP 0 LASTPIN (-8325 1150) $PN BR1
J 2
(-8335 1160);
DISPLAY 0.489362 (-8335 1160);
PAINT MONO (-8335 1160);
FORCEPROP 0 LASTPIN (-8325 1100) $PN BR3
J 2
(-8335 1110);
DISPLAY 0.489362 (-8335 1110);
PAINT MONO (-8335 1110);
FORCEPROP 0 LASTPIN (-8325 1050) $PN BR6
J 2
(-8335 1060);
DISPLAY 0.489362 (-8335 1060);
PAINT MONO (-8335 1060);
FORCEPROP 0 LASTPIN (-8325 1000) $PN BR7
J 2
(-8335 1010);
DISPLAY 0.489362 (-8335 1010);
PAINT MONO (-8335 1010);
FORCEPROP 0 LASTPIN (-8325 950) $PN BR8
J 2
(-8335 960);
DISPLAY 0.489362 (-8335 960);
PAINT MONO (-8335 960);
FORCEPROP 0 LASTPIN (-8325 900) $PN BR10
J 2
(-8335 910);
DISPLAY 0.489362 (-8335 910);
PAINT MONO (-8335 910);
FORCEPROP 0 LASTPIN (-8325 850) $PN BR13
J 2
(-8335 860);
DISPLAY 0.489362 (-8335 860);
PAINT MONO (-8335 860);
FORCEPROP 0 LASTPIN (-8325 800) $PN BR14
J 2
(-8335 810);
DISPLAY 0.489362 (-8335 810);
PAINT MONO (-8335 810);
FORCEPROP 0 LASTPIN (-8325 750) $PN BR15
J 2
(-8335 760);
DISPLAY 0.489362 (-8335 760);
PAINT MONO (-8335 760);
FORCEPROP 0 LASTPIN (-8325 700) $PN BR17
J 2
(-8335 710);
DISPLAY 0.489362 (-8335 710);
PAINT MONO (-8335 710);
FORCEPROP 0 LASTPIN (-8325 650) $PN BR20
J 2
(-8335 660);
DISPLAY 0.489362 (-8335 660);
PAINT MONO (-8335 660);
FORCEPROP 0 LASTPIN (-8325 600) $PN BR21
J 2
(-8335 610);
DISPLAY 0.489362 (-8335 610);
PAINT MONO (-8335 610);
FORCEPROP 0 LASTPIN (-8325 550) $PN BR22
J 2
(-8335 560);
DISPLAY 0.489362 (-8335 560);
PAINT MONO (-8335 560);
FORCEPROP 0 LASTPIN (-8325 500) $PN BR24
J 2
(-8335 510);
DISPLAY 0.489362 (-8335 510);
PAINT MONO (-8335 510);
FORCEPROP 0 LASTPIN (-7225 6400) $PN BR26
J 0
(-7215 6410);
DISPLAY 0.489362 (-7215 6410);
PAINT MONO (-7215 6410);
FORCEPROP 0 LASTPIN (-7225 6350) $PN BR28
J 0
(-7215 6360);
DISPLAY 0.489362 (-7215 6360);
PAINT MONO (-7215 6360);
FORCEPROP 0 LASTPIN (-7225 6300) $PN BR30
J 0
(-7215 6310);
DISPLAY 0.489362 (-7215 6310);
PAINT MONO (-7215 6310);
FORCEPROP 0 LASTPIN (-7225 6250) $PN BR32
J 0
(-7215 6260);
DISPLAY 0.489362 (-7215 6260);
PAINT MONO (-7215 6260);
FORCEPROP 0 LASTPIN (-7225 6200) $PN BR34
J 0
(-7215 6210);
DISPLAY 0.489362 (-7215 6210);
PAINT MONO (-7215 6210);
FORCEPROP 0 LASTPIN (-7225 6150) $PN BR36
J 0
(-7215 6160);
DISPLAY 0.489362 (-7215 6160);
PAINT MONO (-7215 6160);
FORCEPROP 0 LASTPIN (-7225 6100) $PN BR41
J 0
(-7215 6110);
DISPLAY 0.489362 (-7215 6110);
PAINT MONO (-7215 6110);
FORCEPROP 0 LASTPIN (-7225 6050) $PN BR43
J 0
(-7215 6060);
DISPLAY 0.489362 (-7215 6060);
PAINT MONO (-7215 6060);
FORCEPROP 0 LASTPIN (-7225 6000) $PN BR45
J 0
(-7215 6010);
DISPLAY 0.489362 (-7215 6010);
PAINT MONO (-7215 6010);
FORCEPROP 0 LASTPIN (-7225 5950) $PN BR47
J 0
(-7215 5960);
DISPLAY 0.489362 (-7215 5960);
PAINT MONO (-7215 5960);
FORCEPROP 0 LASTPIN (-7225 5900) $PN BR49
J 0
(-7215 5910);
DISPLAY 0.489362 (-7215 5910);
PAINT MONO (-7215 5910);
FORCEPROP 0 LASTPIN (-7225 5850) $PN BR51
J 0
(-7215 5860);
DISPLAY 0.489362 (-7215 5860);
PAINT MONO (-7215 5860);
FORCEPROP 0 LASTPIN (-7225 5800) $PN BR55
J 0
(-7215 5810);
DISPLAY 0.489362 (-7215 5810);
PAINT MONO (-7215 5810);
FORCEPROP 0 LASTPIN (-7225 5750) $PN BR56
J 0
(-7215 5760);
DISPLAY 0.489362 (-7215 5760);
PAINT MONO (-7215 5760);
FORCEPROP 0 LASTPIN (-7225 5700) $PN BR59
J 0
(-7215 5710);
DISPLAY 0.489362 (-7215 5710);
PAINT MONO (-7215 5710);
FORCEPROP 0 LASTPIN (-7225 5650) $PN BR61
J 0
(-7215 5660);
DISPLAY 0.489362 (-7215 5660);
PAINT MONO (-7215 5660);
FORCEPROP 0 LASTPIN (-7225 5600) $PN BR62
J 0
(-7215 5610);
DISPLAY 0.489362 (-7215 5610);
PAINT MONO (-7215 5610);
FORCEPROP 0 LASTPIN (-7225 5550) $PN BR63
J 0
(-7215 5560);
DISPLAY 0.489362 (-7215 5560);
PAINT MONO (-7215 5560);
FORCEPROP 0 LASTPIN (-7225 5500) $PN BR66
J 0
(-7215 5510);
DISPLAY 0.489362 (-7215 5510);
PAINT MONO (-7215 5510);
FORCEPROP 0 LASTPIN (-7225 5450) $PN BR68
J 0
(-7215 5460);
DISPLAY 0.489362 (-7215 5460);
PAINT MONO (-7215 5460);
FORCEPROP 0 LASTPIN (-7225 5400) $PN BR69
J 0
(-7215 5410);
DISPLAY 0.489362 (-7215 5410);
PAINT MONO (-7215 5410);
FORCEPROP 0 LASTPIN (-7225 5350) $PN BR70
J 0
(-7215 5360);
DISPLAY 0.489362 (-7215 5360);
PAINT MONO (-7215 5360);
FORCEPROP 0 LASTPIN (-7225 5300) $PN BR73
J 0
(-7215 5310);
DISPLAY 0.489362 (-7215 5310);
PAINT MONO (-7215 5310);
FORCEPROP 0 LASTPIN (-7225 5250) $PN BR75
J 0
(-7215 5260);
DISPLAY 0.489362 (-7215 5260);
PAINT MONO (-7215 5260);
FORCEPROP 0 LASTPIN (-7225 5200) $PN BT3
J 0
(-7215 5210);
DISPLAY 0.489362 (-7215 5210);
PAINT MONO (-7215 5210);
FORCEPROP 0 LASTPIN (-7225 5150) $PN BT4
J 0
(-7215 5160);
DISPLAY 0.489362 (-7215 5160);
PAINT MONO (-7215 5160);
FORCEPROP 0 LASTPIN (-7225 5100) $PN BT5
J 0
(-7215 5110);
DISPLAY 0.489362 (-7215 5110);
PAINT MONO (-7215 5110);
FORCEPROP 0 LASTPIN (-7225 5050) $PN BT7
J 0
(-7215 5060);
DISPLAY 0.489362 (-7215 5060);
PAINT MONO (-7215 5060);
FORCEPROP 0 LASTPIN (-7225 5000) $PN BT8
J 0
(-7215 5010);
DISPLAY 0.489362 (-7215 5010);
PAINT MONO (-7215 5010);
FORCEPROP 0 LASTPIN (-7225 4950) $PN BT10
J 0
(-7215 4960);
DISPLAY 0.489362 (-7215 4960);
PAINT MONO (-7215 4960);
FORCEPROP 0 LASTPIN (-7225 4900) $PN BT11
J 0
(-7215 4910);
DISPLAY 0.489362 (-7215 4910);
PAINT MONO (-7215 4910);
FORCEPROP 0 LASTPIN (-7225 4850) $PN BT12
J 0
(-7215 4860);
DISPLAY 0.489362 (-7215 4860);
PAINT MONO (-7215 4860);
FORCEPROP 0 LASTPIN (-7225 4800) $PN BT14
J 0
(-7215 4810);
DISPLAY 0.489362 (-7215 4810);
PAINT MONO (-7215 4810);
FORCEPROP 0 LASTPIN (-7225 4750) $PN BT15
J 0
(-7215 4760);
DISPLAY 0.489362 (-7215 4760);
PAINT MONO (-7215 4760);
FORCEPROP 0 LASTPIN (-7225 4700) $PN BT17
J 0
(-7215 4710);
DISPLAY 0.489362 (-7215 4710);
PAINT MONO (-7215 4710);
FORCEPROP 0 LASTPIN (-7225 4650) $PN BT18
J 0
(-7215 4660);
DISPLAY 0.489362 (-7215 4660);
PAINT MONO (-7215 4660);
FORCEPROP 0 LASTPIN (-7225 4600) $PN BT19
J 0
(-7215 4610);
DISPLAY 0.489362 (-7215 4610);
PAINT MONO (-7215 4610);
FORCEPROP 0 LASTPIN (-7225 4550) $PN BT21
J 0
(-7215 4560);
DISPLAY 0.489362 (-7215 4560);
PAINT MONO (-7215 4560);
FORCEPROP 0 LASTPIN (-7225 4500) $PN BT22
J 0
(-7215 4510);
DISPLAY 0.489362 (-7215 4510);
PAINT MONO (-7215 4510);
FORCEPROP 0 LASTPIN (-7225 4450) $PN BT25
J 0
(-7215 4460);
DISPLAY 0.489362 (-7215 4460);
PAINT MONO (-7215 4460);
FORCEPROP 0 LASTPIN (-7225 4400) $PN BT28
J 0
(-7215 4410);
DISPLAY 0.489362 (-7215 4410);
PAINT MONO (-7215 4410);
FORCEPROP 0 LASTPIN (-7225 4350) $PN BT31
J 0
(-7215 4360);
DISPLAY 0.489362 (-7215 4360);
PAINT MONO (-7215 4360);
FORCEPROP 0 LASTPIN (-7225 4300) $PN BT34
J 0
(-7215 4310);
DISPLAY 0.489362 (-7215 4310);
PAINT MONO (-7215 4310);
FORCEPROP 0 LASTPIN (-7225 4250) $PN BT37
J 0
(-7215 4260);
DISPLAY 0.489362 (-7215 4260);
PAINT MONO (-7215 4260);
FORCEPROP 0 LASTPIN (-7225 4200) $PN BT39
J 0
(-7215 4210);
DISPLAY 0.489362 (-7215 4210);
PAINT MONO (-7215 4210);
FORCEPROP 0 LASTPIN (-7225 4150) $PN BT42
J 0
(-7215 4160);
DISPLAY 0.489362 (-7215 4160);
PAINT MONO (-7215 4160);
FORCEPROP 0 LASTPIN (-7225 4100) $PN BT45
J 0
(-7215 4110);
DISPLAY 0.489362 (-7215 4110);
PAINT MONO (-7215 4110);
FORCEPROP 0 LASTPIN (-7225 4050) $PN BT48
J 0
(-7215 4060);
DISPLAY 0.489362 (-7215 4060);
PAINT MONO (-7215 4060);
FORCEPROP 0 LASTPIN (-7225 4000) $PN BT51
J 0
(-7215 4010);
DISPLAY 0.489362 (-7215 4010);
PAINT MONO (-7215 4010);
FORCEPROP 0 LASTPIN (-7225 3950) $PN BT54
J 0
(-7215 3960);
DISPLAY 0.489362 (-7215 3960);
PAINT MONO (-7215 3960);
FORCEPROP 0 LASTPIN (-7225 3900) $PN BT55
J 0
(-7215 3910);
DISPLAY 0.489362 (-7215 3910);
PAINT MONO (-7215 3910);
FORCEPROP 0 LASTPIN (-7225 3850) $PN BT57
J 0
(-7215 3860);
DISPLAY 0.489362 (-7215 3860);
PAINT MONO (-7215 3860);
FORCEPROP 0 LASTPIN (-7225 3800) $PN BT58
J 0
(-7215 3810);
DISPLAY 0.489362 (-7215 3810);
PAINT MONO (-7215 3810);
FORCEPROP 0 LASTPIN (-7225 3750) $PN BT59
J 0
(-7215 3760);
DISPLAY 0.489362 (-7215 3760);
PAINT MONO (-7215 3760);
FORCEPROP 0 LASTPIN (-7225 3700) $PN BT61
J 0
(-7215 3710);
DISPLAY 0.489362 (-7215 3710);
PAINT MONO (-7215 3710);
FORCEPROP 0 LASTPIN (-7225 3650) $PN BT62
J 0
(-7215 3660);
DISPLAY 0.489362 (-7215 3660);
PAINT MONO (-7215 3660);
FORCEPROP 0 LASTPIN (-7225 3600) $PN BT64
J 0
(-7215 3610);
DISPLAY 0.489362 (-7215 3610);
PAINT MONO (-7215 3610);
FORCEPROP 0 LASTPIN (-7225 3550) $PN BT65
J 0
(-7215 3560);
DISPLAY 0.489362 (-7215 3560);
PAINT MONO (-7215 3560);
FORCEPROP 0 LASTPIN (-7225 3500) $PN BT66
J 0
(-7215 3510);
DISPLAY 0.489362 (-7215 3510);
PAINT MONO (-7215 3510);
FORCEPROP 0 LASTPIN (-7225 3450) $PN BT68
J 0
(-7215 3460);
DISPLAY 0.489362 (-7215 3460);
PAINT MONO (-7215 3460);
FORCEPROP 0 LASTPIN (-7225 3400) $PN BT69
J 0
(-7215 3410);
DISPLAY 0.489362 (-7215 3410);
PAINT MONO (-7215 3410);
FORCEPROP 0 LASTPIN (-7225 3350) $PN BT71
J 0
(-7215 3360);
DISPLAY 0.489362 (-7215 3360);
PAINT MONO (-7215 3360);
FORCEPROP 0 LASTPIN (-7225 3300) $PN BT72
J 0
(-7215 3310);
DISPLAY 0.489362 (-7215 3310);
PAINT MONO (-7215 3310);
FORCEPROP 0 LASTPIN (-7225 3250) $PN BT73
J 0
(-7215 3260);
DISPLAY 0.489362 (-7215 3260);
PAINT MONO (-7215 3260);
FORCEPROP 0 LASTPIN (-7225 3200) $PN BU1
J 0
(-7215 3210);
DISPLAY 0.489362 (-7215 3210);
PAINT MONO (-7215 3210);
FORCEPROP 0 LASTPIN (-7225 3150) $PN BU4
J 0
(-7215 3160);
DISPLAY 0.489362 (-7215 3160);
PAINT MONO (-7215 3160);
FORCEPROP 0 LASTPIN (-7225 3100) $PN BU6
J 0
(-7215 3110);
DISPLAY 0.489362 (-7215 3110);
PAINT MONO (-7215 3110);
FORCEPROP 0 LASTPIN (-7225 3050) $PN BU8
J 0
(-7215 3060);
DISPLAY 0.489362 (-7215 3060);
PAINT MONO (-7215 3060);
FORCEPROP 0 LASTPIN (-7225 3000) $PN BU11
J 0
(-7215 3010);
DISPLAY 0.489362 (-7215 3010);
PAINT MONO (-7215 3010);
FORCEPROP 0 LASTPIN (-7225 2950) $PN BU13
J 0
(-7215 2960);
DISPLAY 0.489362 (-7215 2960);
PAINT MONO (-7215 2960);
FORCEPROP 0 LASTPIN (-7225 2900) $PN BU15
J 0
(-7215 2910);
DISPLAY 0.489362 (-7215 2910);
PAINT MONO (-7215 2910);
FORCEPROP 0 LASTPIN (-7225 2850) $PN BU18
J 0
(-7215 2860);
DISPLAY 0.489362 (-7215 2860);
PAINT MONO (-7215 2860);
FORCEPROP 0 LASTPIN (-7225 2800) $PN BU20
J 0
(-7215 2810);
DISPLAY 0.489362 (-7215 2810);
PAINT MONO (-7215 2810);
FORCEPROP 0 LASTPIN (-7225 2750) $PN BU22
J 0
(-7215 2760);
DISPLAY 0.489362 (-7215 2760);
PAINT MONO (-7215 2760);
FORCEPROP 0 LASTPIN (-7225 2700) $PN BU25
J 0
(-7215 2710);
DISPLAY 0.489362 (-7215 2710);
PAINT MONO (-7215 2710);
FORCEPROP 0 LASTPIN (-7225 2650) $PN BU28
J 0
(-7215 2660);
DISPLAY 0.489362 (-7215 2660);
PAINT MONO (-7215 2660);
FORCEPROP 0 LASTPIN (-7225 2600) $PN BU31
J 0
(-7215 2610);
DISPLAY 0.489362 (-7215 2610);
PAINT MONO (-7215 2610);
FORCEPROP 0 LASTPIN (-7225 2550) $PN BU34
J 0
(-7215 2560);
DISPLAY 0.489362 (-7215 2560);
PAINT MONO (-7215 2560);
FORCEPROP 0 LASTPIN (-7225 2500) $PN BU35
J 0
(-7215 2510);
DISPLAY 0.489362 (-7215 2510);
PAINT MONO (-7215 2510);
FORCEPROP 0 LASTPIN (-7225 2450) $PN BU36
J 0
(-7215 2460);
DISPLAY 0.489362 (-7215 2460);
PAINT MONO (-7215 2460);
FORCEPROP 0 LASTPIN (-7225 2400) $PN BU40
J 0
(-7215 2410);
DISPLAY 0.489362 (-7215 2410);
PAINT MONO (-7215 2410);
FORCEPROP 0 LASTPIN (-7225 2350) $PN BU41
J 0
(-7215 2360);
DISPLAY 0.489362 (-7215 2360);
PAINT MONO (-7215 2360);
FORCEPROP 0 LASTPIN (-7225 2300) $PN BU42
J 0
(-7215 2310);
DISPLAY 0.489362 (-7215 2310);
PAINT MONO (-7215 2310);
FORCEPROP 0 LASTPIN (-7225 2250) $PN BU45
J 0
(-7215 2260);
DISPLAY 0.489362 (-7215 2260);
PAINT MONO (-7215 2260);
FORCEPROP 0 LASTPIN (-7225 2200) $PN BU48
J 0
(-7215 2210);
DISPLAY 0.489362 (-7215 2210);
PAINT MONO (-7215 2210);
FORCEPROP 0 LASTPIN (-7225 2150) $PN BU51
J 0
(-7215 2160);
DISPLAY 0.489362 (-7215 2160);
PAINT MONO (-7215 2160);
FORCEPROP 0 LASTPIN (-7225 2100) $PN BU54
J 0
(-7215 2110);
DISPLAY 0.489362 (-7215 2110);
PAINT MONO (-7215 2110);
FORCEPROP 0 LASTPIN (-7225 2050) $PN BU56
J 0
(-7215 2060);
DISPLAY 0.489362 (-7215 2060);
PAINT MONO (-7215 2060);
FORCEPROP 0 LASTPIN (-7225 2000) $PN BU58
J 0
(-7215 2010);
DISPLAY 0.489362 (-7215 2010);
PAINT MONO (-7215 2010);
FORCEPROP 0 LASTPIN (-7225 1950) $PN BU61
J 0
(-7215 1960);
DISPLAY 0.489362 (-7215 1960);
PAINT MONO (-7215 1960);
FORCEPROP 0 LASTPIN (-7225 1900) $PN BU63
J 0
(-7215 1910);
DISPLAY 0.489362 (-7215 1910);
PAINT MONO (-7215 1910);
FORCEPROP 0 LASTPIN (-7225 1850) $PN BU65
J 0
(-7215 1860);
DISPLAY 0.489362 (-7215 1860);
PAINT MONO (-7215 1860);
FORCEPROP 0 LASTPIN (-7225 1800) $PN BU68
J 0
(-7215 1810);
DISPLAY 0.489362 (-7215 1810);
PAINT MONO (-7215 1810);
FORCEPROP 0 LASTPIN (-7225 1750) $PN BU70
J 0
(-7215 1760);
DISPLAY 0.489362 (-7215 1760);
PAINT MONO (-7215 1760);
FORCEPROP 0 LASTPIN (-7225 1700) $PN BU72
J 0
(-7215 1710);
DISPLAY 0.489362 (-7215 1710);
PAINT MONO (-7215 1710);
FORCEPROP 0 LASTPIN (-7225 1650) $PN BU75
J 0
(-7215 1660);
DISPLAY 0.489362 (-7215 1660);
PAINT MONO (-7215 1660);
FORCEPROP 0 LASTPIN (-7225 1600) $PN BV3
J 0
(-7215 1610);
DISPLAY 0.489362 (-7215 1610);
PAINT MONO (-7215 1610);
FORCEPROP 0 LASTPIN (-7225 1550) $PN BV8
J 0
(-7215 1560);
DISPLAY 0.489362 (-7215 1560);
PAINT MONO (-7215 1560);
FORCEPROP 0 LASTPIN (-7225 1500) $PN BV10
J 0
(-7215 1510);
DISPLAY 0.489362 (-7215 1510);
PAINT MONO (-7215 1510);
FORCEPROP 0 LASTPIN (-7225 1450) $PN BV15
J 0
(-7215 1460);
DISPLAY 0.489362 (-7215 1460);
PAINT MONO (-7215 1460);
FORCEPROP 0 LASTPIN (-7225 1400) $PN BV17
J 0
(-7215 1410);
DISPLAY 0.489362 (-7215 1410);
PAINT MONO (-7215 1410);
FORCEPROP 0 LASTPIN (-7225 1350) $PN BV23
J 0
(-7215 1360);
DISPLAY 0.489362 (-7215 1360);
PAINT MONO (-7215 1360);
FORCEPROP 0 LASTPIN (-7225 1300) $PN BV24
J 0
(-7215 1310);
DISPLAY 0.489362 (-7215 1310);
PAINT MONO (-7215 1310);
FORCEPROP 0 LASTPIN (-7225 1250) $PN BV25
J 0
(-7215 1260);
DISPLAY 0.489362 (-7215 1260);
PAINT MONO (-7215 1260);
FORCEPROP 0 LASTPIN (-7225 1200) $PN BV26
J 0
(-7215 1210);
DISPLAY 0.489362 (-7215 1210);
PAINT MONO (-7215 1210);
FORCEPROP 0 LASTPIN (-7225 1150) $PN BV27
J 0
(-7215 1160);
DISPLAY 0.489362 (-7215 1160);
PAINT MONO (-7215 1160);
FORCEPROP 0 LASTPIN (-7225 1100) $PN BV28
J 0
(-7215 1110);
DISPLAY 0.489362 (-7215 1110);
PAINT MONO (-7215 1110);
FORCEPROP 0 LASTPIN (-7225 1050) $PN BV29
J 0
(-7215 1060);
DISPLAY 0.489362 (-7215 1060);
PAINT MONO (-7215 1060);
FORCEPROP 0 LASTPIN (-7225 1000) $PN BV30
J 0
(-7215 1010);
DISPLAY 0.489362 (-7215 1010);
PAINT MONO (-7215 1010);
FORCEPROP 0 LASTPIN (-7225 950) $PN BV31
J 0
(-7215 960);
DISPLAY 0.489362 (-7215 960);
PAINT MONO (-7215 960);
FORCEPROP 0 LASTPIN (-7225 900) $PN BV32
J 0
(-7215 910);
DISPLAY 0.489362 (-7215 910);
PAINT MONO (-7215 910);
FORCEPROP 0 LASTPIN (-7225 850) $PN BV33
J 0
(-7215 860);
DISPLAY 0.489362 (-7215 860);
PAINT MONO (-7215 860);
FORCEPROP 0 LASTPIN (-7225 800) $PN BV34
J 0
(-7215 810);
DISPLAY 0.489362 (-7215 810);
PAINT MONO (-7215 810);
FORCEPROP 0 LASTPIN (-7225 750) $PN BV37
J 0
(-7215 760);
DISPLAY 0.489362 (-7215 760);
PAINT MONO (-7215 760);
FORCEPROP 0 LASTPIN (-7225 700) $PN BV39
J 0
(-7215 710);
DISPLAY 0.489362 (-7215 710);
PAINT MONO (-7215 710);
FORCEPROP 0 LASTPIN (-7225 650) $PN BV43
J 0
(-7215 660);
DISPLAY 0.489362 (-7215 660);
PAINT MONO (-7215 660);
FORCEPROP 0 LASTPIN (-7225 600) $PN BV44
J 0
(-7215 610);
DISPLAY 0.489362 (-7215 610);
PAINT MONO (-7215 610);
FORCEPROP 0 LASTPIN (-7225 550) $PN BV45
J 0
(-7215 560);
DISPLAY 0.489362 (-7215 560);
PAINT MONO (-7215 560);
FORCEPROP 2 LAST PART_TYPE SMLF
J 0
(-8175 6700);
DISPLAY 1.021277 (-8175 6700);
FORCEPROP 1 LAST MATERIAL IO
J 0
(-8170 6532);
DISPLAY 0.489362 (-8170 6532);
PAINT SKYBLUE (-8170 6532);
FORCEPROP 2 LAST VALUE SOCKET6096_13568-001
J 0
(-8175 6575);
DISPLAY 0.489362 (-8175 6575);
PAINT SKYBLUE (-8175 6575);
FORCEPROP 1 LAST NEEDS_NO_SIZE TRUE
J 0
(-7775 3450);
DISPLAY 0.723404 (-7775 3450);
PAINT GREEN (-7775 3450);
DISPLAY INVISIBLE (-7775 3450);
FORCEPROP 1 LAST CDS_LMAN_SYM_OUTLINE -400,3050,400,-3050
J 0
(-7775 3450);
DISPLAY 0.468085 (-7775 3450);
PAINT GREEN (-7775 3450);
DISPLAY INVISIBLE (-7775 3450);
FORCEPROP 2 LAST CDS_LIB pure_quanta
J 0
(-7775 3450);
DISPLAY INVISIBLE (-7775 3450);
FORCEPROP 1 LAST PATH I13
J 0
(-7775 3450);
DISPLAY 0.723404 (-7775 3450);
PAINT GREEN (-7775 3450);
DISPLAY INVISIBLE (-7775 3450);
FORCEPROP 1 LAST PART_NUMBER DGA^6000030
J 0
(-8175 6650);
DISPLAY 0.489362 (-8175 6650);
PAINT SKYBLUE (-8175 6650);
DISPLAY INVISIBLE (-8175 6650);
FORCEADD GENOA_SP5..37
(-5750 3450);
FORCEPROP 1 LAST LOCATION U25
J 0
(-6145 6600);
DISPLAY 0.489362 (-6145 6600);
PAINT SKYBLUE (-6145 6600);
FORCEPROP 0 LAST $SEC 37
J 0
(-6125 6850);
DISPLAY 0.680851 (-6125 6850);
PAINT MONO (-6125 6850);
DISPLAY INVISIBLE (-6125 6850);
FORCEPROP 0 LAST CDS_SEC 37
J 0
(-6325 6725);
DISPLAY 1.021277 (-6325 6725);
DISPLAY INVISIBLE (-6325 6725);
FORCEPROP 0 LASTPIN (-6300 6350) $PN BV46
J 2
(-6310 6360);
DISPLAY 0.489362 (-6310 6360);
PAINT MONO (-6310 6360);
FORCEPROP 0 LASTPIN (-6300 6300) $PN BV47
J 2
(-6310 6310);
DISPLAY 0.489362 (-6310 6310);
PAINT MONO (-6310 6310);
FORCEPROP 0 LASTPIN (-6300 6250) $PN BV48
J 2
(-6310 6260);
DISPLAY 0.489362 (-6310 6260);
PAINT MONO (-6310 6260);
FORCEPROP 0 LASTPIN (-6300 6200) $PN BV49
J 2
(-6310 6210);
DISPLAY 0.489362 (-6310 6210);
PAINT MONO (-6310 6210);
FORCEPROP 0 LASTPIN (-6300 6150) $PN BV50
J 2
(-6310 6160);
DISPLAY 0.489362 (-6310 6160);
PAINT MONO (-6310 6160);
FORCEPROP 0 LASTPIN (-6300 6100) $PN BV51
J 2
(-6310 6110);
DISPLAY 0.489362 (-6310 6110);
PAINT MONO (-6310 6110);
FORCEPROP 0 LASTPIN (-6300 6050) $PN BV52
J 2
(-6310 6060);
DISPLAY 0.489362 (-6310 6060);
PAINT MONO (-6310 6060);
FORCEPROP 0 LASTPIN (-6300 6000) $PN BV53
J 2
(-6310 6010);
DISPLAY 0.489362 (-6310 6010);
PAINT MONO (-6310 6010);
FORCEPROP 0 LASTPIN (-6300 5950) $PN BV59
J 2
(-6310 5960);
DISPLAY 0.489362 (-6310 5960);
PAINT MONO (-6310 5960);
FORCEPROP 0 LASTPIN (-6300 5900) $PN BV61
J 2
(-6310 5910);
DISPLAY 0.489362 (-6310 5910);
PAINT MONO (-6310 5910);
FORCEPROP 0 LASTPIN (-6300 5850) $PN BV66
J 2
(-6310 5860);
DISPLAY 0.489362 (-6310 5860);
PAINT MONO (-6310 5860);
FORCEPROP 0 LASTPIN (-6300 5800) $PN BV68
J 2
(-6310 5810);
DISPLAY 0.489362 (-6310 5810);
PAINT MONO (-6310 5810);
FORCEPROP 0 LASTPIN (-6300 5750) $PN BV73
J 2
(-6310 5760);
DISPLAY 0.489362 (-6310 5760);
PAINT MONO (-6310 5760);
FORCEPROP 0 LASTPIN (-6300 5700) $PN BW1
J 2
(-6310 5710);
DISPLAY 0.489362 (-6310 5710);
PAINT MONO (-6310 5710);
FORCEPROP 0 LASTPIN (-6300 5650) $PN BW4
J 2
(-6310 5660);
DISPLAY 0.489362 (-6310 5660);
PAINT MONO (-6310 5660);
FORCEPROP 0 LASTPIN (-6300 5600) $PN BW6
J 2
(-6310 5610);
DISPLAY 0.489362 (-6310 5610);
PAINT MONO (-6310 5610);
FORCEPROP 0 LASTPIN (-6300 5550) $PN BW8
J 2
(-6310 5560);
DISPLAY 0.489362 (-6310 5560);
PAINT MONO (-6310 5560);
FORCEPROP 0 LASTPIN (-6300 5500) $PN BW11
J 2
(-6310 5510);
DISPLAY 0.489362 (-6310 5510);
PAINT MONO (-6310 5510);
FORCEPROP 0 LASTPIN (-6300 5450) $PN BW13
J 2
(-6310 5460);
DISPLAY 0.489362 (-6310 5460);
PAINT MONO (-6310 5460);
FORCEPROP 0 LASTPIN (-6300 5400) $PN BW15
J 2
(-6310 5410);
DISPLAY 0.489362 (-6310 5410);
PAINT MONO (-6310 5410);
FORCEPROP 0 LASTPIN (-6300 5350) $PN BW18
J 2
(-6310 5360);
DISPLAY 0.489362 (-6310 5360);
PAINT MONO (-6310 5360);
FORCEPROP 0 LASTPIN (-6300 5300) $PN BW20
J 2
(-6310 5310);
DISPLAY 0.489362 (-6310 5310);
PAINT MONO (-6310 5310);
FORCEPROP 0 LASTPIN (-6300 5250) $PN BW22
J 2
(-6310 5260);
DISPLAY 0.489362 (-6310 5260);
PAINT MONO (-6310 5260);
FORCEPROP 0 LASTPIN (-6300 5200) $PN BW28
J 2
(-6310 5210);
DISPLAY 0.489362 (-6310 5210);
PAINT MONO (-6310 5210);
FORCEPROP 0 LASTPIN (-6300 5150) $PN BW31
J 2
(-6310 5160);
DISPLAY 0.489362 (-6310 5160);
PAINT MONO (-6310 5160);
FORCEPROP 0 LASTPIN (-6300 5100) $PN BW34
J 2
(-6310 5110);
DISPLAY 0.489362 (-6310 5110);
PAINT MONO (-6310 5110);
FORCEPROP 0 LASTPIN (-6300 5050) $PN BW42
J 2
(-6310 5060);
DISPLAY 0.489362 (-6310 5060);
PAINT MONO (-6310 5060);
FORCEPROP 0 LASTPIN (-6300 5000) $PN BW45
J 2
(-6310 5010);
DISPLAY 0.489362 (-6310 5010);
PAINT MONO (-6310 5010);
FORCEPROP 0 LASTPIN (-6300 4950) $PN BW48
J 2
(-6310 4960);
DISPLAY 0.489362 (-6310 4960);
PAINT MONO (-6310 4960);
FORCEPROP 0 LASTPIN (-6300 4900) $PN BW51
J 2
(-6310 4910);
DISPLAY 0.489362 (-6310 4910);
PAINT MONO (-6310 4910);
FORCEPROP 0 LASTPIN (-6300 4850) $PN BW54
J 2
(-6310 4860);
DISPLAY 0.489362 (-6310 4860);
PAINT MONO (-6310 4860);
FORCEPROP 0 LASTPIN (-6300 4800) $PN BW56
J 2
(-6310 4810);
DISPLAY 0.489362 (-6310 4810);
PAINT MONO (-6310 4810);
FORCEPROP 0 LASTPIN (-6300 4750) $PN BW58
J 2
(-6310 4760);
DISPLAY 0.489362 (-6310 4760);
PAINT MONO (-6310 4760);
FORCEPROP 0 LASTPIN (-6300 4700) $PN BW61
J 2
(-6310 4710);
DISPLAY 0.489362 (-6310 4710);
PAINT MONO (-6310 4710);
FORCEPROP 0 LASTPIN (-6300 4650) $PN BW63
J 2
(-6310 4660);
DISPLAY 0.489362 (-6310 4660);
PAINT MONO (-6310 4660);
FORCEPROP 0 LASTPIN (-6300 4600) $PN BW65
J 2
(-6310 4610);
DISPLAY 0.489362 (-6310 4610);
PAINT MONO (-6310 4610);
FORCEPROP 0 LASTPIN (-6300 4550) $PN BW68
J 2
(-6310 4560);
DISPLAY 0.489362 (-6310 4560);
PAINT MONO (-6310 4560);
FORCEPROP 0 LASTPIN (-6300 4500) $PN BW70
J 2
(-6310 4510);
DISPLAY 0.489362 (-6310 4510);
PAINT MONO (-6310 4510);
FORCEPROP 0 LASTPIN (-6300 4450) $PN BW72
J 2
(-6310 4460);
DISPLAY 0.489362 (-6310 4460);
PAINT MONO (-6310 4460);
FORCEPROP 0 LASTPIN (-6300 4400) $PN BW75
J 2
(-6310 4410);
DISPLAY 0.489362 (-6310 4410);
PAINT MONO (-6310 4410);
FORCEPROP 0 LASTPIN (-6300 4350) $PN BY3
J 2
(-6310 4360);
DISPLAY 0.489362 (-6310 4360);
PAINT MONO (-6310 4360);
FORCEPROP 0 LASTPIN (-6300 4300) $PN BY5
J 2
(-6310 4310);
DISPLAY 0.489362 (-6310 4310);
PAINT MONO (-6310 4310);
FORCEPROP 0 LASTPIN (-6300 4250) $PN BY8
J 2
(-6310 4260);
DISPLAY 0.489362 (-6310 4260);
PAINT MONO (-6310 4260);
FORCEPROP 0 LASTPIN (-6300 4200) $PN BY10
J 2
(-6310 4210);
DISPLAY 0.489362 (-6310 4210);
PAINT MONO (-6310 4210);
FORCEPROP 0 LASTPIN (-6300 4150) $PN BY12
J 2
(-6310 4160);
DISPLAY 0.489362 (-6310 4160);
PAINT MONO (-6310 4160);
FORCEPROP 0 LASTPIN (-6300 4100) $PN BY15
J 2
(-6310 4110);
DISPLAY 0.489362 (-6310 4110);
PAINT MONO (-6310 4110);
FORCEPROP 0 LASTPIN (-6300 4050) $PN BY17
J 2
(-6310 4060);
DISPLAY 0.489362 (-6310 4060);
PAINT MONO (-6310 4060);
FORCEPROP 0 LASTPIN (-6300 4000) $PN BY19
J 2
(-6310 4010);
DISPLAY 0.489362 (-6310 4010);
PAINT MONO (-6310 4010);
FORCEPROP 0 LASTPIN (-6300 3950) $PN BY22
J 2
(-6310 3960);
DISPLAY 0.489362 (-6310 3960);
PAINT MONO (-6310 3960);
FORCEPROP 0 LASTPIN (-6300 3900) $PN BY25
J 2
(-6310 3910);
DISPLAY 0.489362 (-6310 3910);
PAINT MONO (-6310 3910);
FORCEPROP 0 LASTPIN (-6300 3850) $PN BY28
J 2
(-6310 3860);
DISPLAY 0.489362 (-6310 3860);
PAINT MONO (-6310 3860);
FORCEPROP 0 LASTPIN (-6300 3800) $PN BY31
J 2
(-6310 3810);
DISPLAY 0.489362 (-6310 3810);
PAINT MONO (-6310 3810);
FORCEPROP 0 LASTPIN (-6300 3750) $PN BY34
J 2
(-6310 3760);
DISPLAY 0.489362 (-6310 3760);
PAINT MONO (-6310 3760);
FORCEPROP 0 LASTPIN (-6300 3700) $PN BY37
J 2
(-6310 3710);
DISPLAY 0.489362 (-6310 3710);
PAINT MONO (-6310 3710);
FORCEPROP 0 LASTPIN (-6300 3650) $PN BY39
J 2
(-6310 3660);
DISPLAY 0.489362 (-6310 3660);
PAINT MONO (-6310 3660);
FORCEPROP 0 LASTPIN (-6300 3600) $PN BY42
J 2
(-6310 3610);
DISPLAY 0.489362 (-6310 3610);
PAINT MONO (-6310 3610);
FORCEPROP 0 LASTPIN (-6300 3550) $PN BY45
J 2
(-6310 3560);
DISPLAY 0.489362 (-6310 3560);
PAINT MONO (-6310 3560);
FORCEPROP 0 LASTPIN (-6300 3500) $PN BY48
J 2
(-6310 3510);
DISPLAY 0.489362 (-6310 3510);
PAINT MONO (-6310 3510);
FORCEPROP 0 LASTPIN (-6300 3450) $PN BY51
J 2
(-6310 3460);
DISPLAY 0.489362 (-6310 3460);
PAINT MONO (-6310 3460);
FORCEPROP 0 LASTPIN (-6300 3400) $PN BY54
J 2
(-6310 3410);
DISPLAY 0.489362 (-6310 3410);
PAINT MONO (-6310 3410);
FORCEPROP 0 LASTPIN (-6300 3350) $PN BY57
J 2
(-6310 3360);
DISPLAY 0.489362 (-6310 3360);
PAINT MONO (-6310 3360);
FORCEPROP 0 LASTPIN (-6300 3300) $PN BY59
J 2
(-6310 3310);
DISPLAY 0.489362 (-6310 3310);
PAINT MONO (-6310 3310);
FORCEPROP 0 LASTPIN (-6300 3250) $PN BY61
J 2
(-6310 3260);
DISPLAY 0.489362 (-6310 3260);
PAINT MONO (-6310 3260);
FORCEPROP 0 LASTPIN (-6300 3200) $PN BY64
J 2
(-6310 3210);
DISPLAY 0.489362 (-6310 3210);
PAINT MONO (-6310 3210);
FORCEPROP 0 LASTPIN (-6300 3150) $PN BY66
J 2
(-6310 3160);
DISPLAY 0.489362 (-6310 3160);
PAINT MONO (-6310 3160);
FORCEPROP 0 LASTPIN (-6300 3100) $PN BY68
J 2
(-6310 3110);
DISPLAY 0.489362 (-6310 3110);
PAINT MONO (-6310 3110);
FORCEPROP 0 LASTPIN (-6300 3050) $PN BY71
J 2
(-6310 3060);
DISPLAY 0.489362 (-6310 3060);
PAINT MONO (-6310 3060);
FORCEPROP 0 LASTPIN (-6300 3000) $PN BY73
J 2
(-6310 3010);
DISPLAY 0.489362 (-6310 3010);
PAINT MONO (-6310 3010);
FORCEPROP 0 LASTPIN (-6300 2950) $PN CA1
J 2
(-6310 2960);
DISPLAY 0.489362 (-6310 2960);
PAINT MONO (-6310 2960);
FORCEPROP 0 LASTPIN (-6300 2900) $PN CA6
J 2
(-6310 2910);
DISPLAY 0.489362 (-6310 2910);
PAINT MONO (-6310 2910);
FORCEPROP 0 LASTPIN (-6300 2850) $PN CA8
J 2
(-6310 2860);
DISPLAY 0.489362 (-6310 2860);
PAINT MONO (-6310 2860);
FORCEPROP 0 LASTPIN (-6300 2800) $PN CA13
J 2
(-6310 2810);
DISPLAY 0.489362 (-6310 2810);
PAINT MONO (-6310 2810);
FORCEPROP 0 LASTPIN (-6300 2750) $PN CA15
J 2
(-6310 2760);
DISPLAY 0.489362 (-6310 2760);
PAINT MONO (-6310 2760);
FORCEPROP 0 LASTPIN (-6300 2700) $PN CA20
J 2
(-6310 2710);
DISPLAY 0.489362 (-6310 2710);
PAINT MONO (-6310 2710);
FORCEPROP 0 LASTPIN (-6300 2650) $PN CA22
J 2
(-6310 2660);
DISPLAY 0.489362 (-6310 2660);
PAINT MONO (-6310 2660);
FORCEPROP 0 LASTPIN (-6300 2600) $PN CA25
J 2
(-6310 2610);
DISPLAY 0.489362 (-6310 2610);
PAINT MONO (-6310 2610);
FORCEPROP 0 LASTPIN (-6300 2550) $PN CA28
J 2
(-6310 2560);
DISPLAY 0.489362 (-6310 2560);
PAINT MONO (-6310 2560);
FORCEPROP 0 LASTPIN (-6300 2500) $PN CA31
J 2
(-6310 2510);
DISPLAY 0.489362 (-6310 2510);
PAINT MONO (-6310 2510);
FORCEPROP 0 LASTPIN (-6300 2450) $PN CA34
J 2
(-6310 2460);
DISPLAY 0.489362 (-6310 2460);
PAINT MONO (-6310 2460);
FORCEPROP 0 LASTPIN (-6300 2400) $PN CA35
J 2
(-6310 2410);
DISPLAY 0.489362 (-6310 2410);
PAINT MONO (-6310 2410);
FORCEPROP 0 LASTPIN (-6300 2350) $PN CA36
J 2
(-6310 2360);
DISPLAY 0.489362 (-6310 2360);
PAINT MONO (-6310 2360);
FORCEPROP 0 LASTPIN (-6300 2300) $PN CA40
J 2
(-6310 2310);
DISPLAY 0.489362 (-6310 2310);
PAINT MONO (-6310 2310);
FORCEPROP 0 LASTPIN (-6300 2250) $PN CA41
J 2
(-6310 2260);
DISPLAY 0.489362 (-6310 2260);
PAINT MONO (-6310 2260);
FORCEPROP 0 LASTPIN (-6300 2200) $PN CA42
J 2
(-6310 2210);
DISPLAY 0.489362 (-6310 2210);
PAINT MONO (-6310 2210);
FORCEPROP 0 LASTPIN (-6300 2150) $PN CA45
J 2
(-6310 2160);
DISPLAY 0.489362 (-6310 2160);
PAINT MONO (-6310 2160);
FORCEPROP 0 LASTPIN (-6300 2100) $PN CA48
J 2
(-6310 2110);
DISPLAY 0.489362 (-6310 2110);
PAINT MONO (-6310 2110);
FORCEPROP 0 LASTPIN (-6300 2050) $PN CA51
J 2
(-6310 2060);
DISPLAY 0.489362 (-6310 2060);
PAINT MONO (-6310 2060);
FORCEPROP 0 LASTPIN (-6300 2000) $PN CA54
J 2
(-6310 2010);
DISPLAY 0.489362 (-6310 2010);
PAINT MONO (-6310 2010);
FORCEPROP 0 LASTPIN (-6300 1950) $PN CA56
J 2
(-6310 1960);
DISPLAY 0.489362 (-6310 1960);
PAINT MONO (-6310 1960);
FORCEPROP 0 LASTPIN (-6300 1900) $PN CA61
J 2
(-6310 1910);
DISPLAY 0.489362 (-6310 1910);
PAINT MONO (-6310 1910);
FORCEPROP 0 LASTPIN (-6300 1850) $PN CA63
J 2
(-6310 1860);
DISPLAY 0.489362 (-6310 1860);
PAINT MONO (-6310 1860);
FORCEPROP 0 LASTPIN (-6300 1800) $PN CA68
J 2
(-6310 1810);
DISPLAY 0.489362 (-6310 1810);
PAINT MONO (-6310 1810);
FORCEPROP 0 LASTPIN (-6300 1750) $PN CA70
J 2
(-6310 1760);
DISPLAY 0.489362 (-6310 1760);
PAINT MONO (-6310 1760);
FORCEPROP 0 LASTPIN (-6300 1700) $PN CA75
J 2
(-6310 1710);
DISPLAY 0.489362 (-6310 1710);
PAINT MONO (-6310 1710);
FORCEPROP 0 LASTPIN (-6300 1650) $PN CB3
J 2
(-6310 1660);
DISPLAY 0.489362 (-6310 1660);
PAINT MONO (-6310 1660);
FORCEPROP 0 LASTPIN (-6300 1600) $PN CB5
J 2
(-6310 1610);
DISPLAY 0.489362 (-6310 1610);
PAINT MONO (-6310 1610);
FORCEPROP 0 LASTPIN (-6300 1550) $PN CB8
J 2
(-6310 1560);
DISPLAY 0.489362 (-6310 1560);
PAINT MONO (-6310 1560);
FORCEPROP 0 LASTPIN (-6300 1500) $PN CB10
J 2
(-6310 1510);
DISPLAY 0.489362 (-6310 1510);
PAINT MONO (-6310 1510);
FORCEPROP 0 LASTPIN (-6300 1450) $PN CB12
J 2
(-6310 1460);
DISPLAY 0.489362 (-6310 1460);
PAINT MONO (-6310 1460);
FORCEPROP 0 LASTPIN (-6300 1400) $PN CB15
J 2
(-6310 1410);
DISPLAY 0.489362 (-6310 1410);
PAINT MONO (-6310 1410);
FORCEPROP 0 LASTPIN (-6300 1350) $PN CB17
J 2
(-6310 1360);
DISPLAY 0.489362 (-6310 1360);
PAINT MONO (-6310 1360);
FORCEPROP 0 LASTPIN (-6300 1300) $PN CB19
J 2
(-6310 1310);
DISPLAY 0.489362 (-6310 1310);
PAINT MONO (-6310 1310);
FORCEPROP 0 LASTPIN (-6300 1250) $PN CB23
J 2
(-6310 1260);
DISPLAY 0.489362 (-6310 1260);
PAINT MONO (-6310 1260);
FORCEPROP 0 LASTPIN (-6300 1200) $PN CB24
J 2
(-6310 1210);
DISPLAY 0.489362 (-6310 1210);
PAINT MONO (-6310 1210);
FORCEPROP 0 LASTPIN (-6300 1150) $PN CB25
J 2
(-6310 1160);
DISPLAY 0.489362 (-6310 1160);
PAINT MONO (-6310 1160);
FORCEPROP 0 LASTPIN (-6300 1100) $PN CB26
J 2
(-6310 1110);
DISPLAY 0.489362 (-6310 1110);
PAINT MONO (-6310 1110);
FORCEPROP 0 LASTPIN (-6300 1050) $PN CB27
J 2
(-6310 1060);
DISPLAY 0.489362 (-6310 1060);
PAINT MONO (-6310 1060);
FORCEPROP 0 LASTPIN (-6300 1000) $PN CB28
J 2
(-6310 1010);
DISPLAY 0.489362 (-6310 1010);
PAINT MONO (-6310 1010);
FORCEPROP 0 LASTPIN (-6300 950) $PN CB29
J 2
(-6310 960);
DISPLAY 0.489362 (-6310 960);
PAINT MONO (-6310 960);
FORCEPROP 0 LASTPIN (-6300 900) $PN CB30
J 2
(-6310 910);
DISPLAY 0.489362 (-6310 910);
PAINT MONO (-6310 910);
FORCEPROP 0 LASTPIN (-6300 850) $PN CB31
J 2
(-6310 860);
DISPLAY 0.489362 (-6310 860);
PAINT MONO (-6310 860);
FORCEPROP 0 LASTPIN (-6300 800) $PN CB32
J 2
(-6310 810);
DISPLAY 0.489362 (-6310 810);
PAINT MONO (-6310 810);
FORCEPROP 0 LASTPIN (-6300 750) $PN CB33
J 2
(-6310 760);
DISPLAY 0.489362 (-6310 760);
PAINT MONO (-6310 760);
FORCEPROP 0 LASTPIN (-6300 700) $PN CB34
J 2
(-6310 710);
DISPLAY 0.489362 (-6310 710);
PAINT MONO (-6310 710);
FORCEPROP 0 LASTPIN (-6300 650) $PN CB37
J 2
(-6310 660);
DISPLAY 0.489362 (-6310 660);
PAINT MONO (-6310 660);
FORCEPROP 0 LASTPIN (-6300 600) $PN CB39
J 2
(-6310 610);
DISPLAY 0.489362 (-6310 610);
PAINT MONO (-6310 610);
FORCEPROP 0 LASTPIN (-6300 550) $PN CB42
J 2
(-6310 560);
DISPLAY 0.489362 (-6310 560);
PAINT MONO (-6310 560);
FORCEPROP 0 LASTPIN (-6300 500) $PN CB43
J 2
(-6310 510);
DISPLAY 0.489362 (-6310 510);
PAINT MONO (-6310 510);
FORCEPROP 0 LASTPIN (-5200 6300) $PN CB45
J 0
(-5190 6310);
DISPLAY 0.489362 (-5190 6310);
PAINT MONO (-5190 6310);
FORCEPROP 0 LASTPIN (-5200 6250) $PN CB46
J 0
(-5190 6260);
DISPLAY 0.489362 (-5190 6260);
PAINT MONO (-5190 6260);
FORCEPROP 0 LASTPIN (-5200 6200) $PN CB47
J 0
(-5190 6210);
DISPLAY 0.489362 (-5190 6210);
PAINT MONO (-5190 6210);
FORCEPROP 0 LASTPIN (-5200 6150) $PN CB48
J 0
(-5190 6160);
DISPLAY 0.489362 (-5190 6160);
PAINT MONO (-5190 6160);
FORCEPROP 0 LASTPIN (-5200 6100) $PN CB49
J 0
(-5190 6110);
DISPLAY 0.489362 (-5190 6110);
PAINT MONO (-5190 6110);
FORCEPROP 0 LASTPIN (-5200 6050) $PN CB50
J 0
(-5190 6060);
DISPLAY 0.489362 (-5190 6060);
PAINT MONO (-5190 6060);
FORCEPROP 0 LASTPIN (-5200 6000) $PN CB51
J 0
(-5190 6010);
DISPLAY 0.489362 (-5190 6010);
PAINT MONO (-5190 6010);
FORCEPROP 0 LASTPIN (-5200 5950) $PN CB52
J 0
(-5190 5960);
DISPLAY 0.489362 (-5190 5960);
PAINT MONO (-5190 5960);
FORCEPROP 0 LASTPIN (-5200 5900) $PN CB53
J 0
(-5190 5910);
DISPLAY 0.489362 (-5190 5910);
PAINT MONO (-5190 5910);
FORCEPROP 0 LASTPIN (-5200 5850) $PN CB57
J 0
(-5190 5860);
DISPLAY 0.489362 (-5190 5860);
PAINT MONO (-5190 5860);
FORCEPROP 0 LASTPIN (-5200 5800) $PN CB59
J 0
(-5190 5810);
DISPLAY 0.489362 (-5190 5810);
PAINT MONO (-5190 5810);
FORCEPROP 0 LASTPIN (-5200 5750) $PN CB61
J 0
(-5190 5760);
DISPLAY 0.489362 (-5190 5760);
PAINT MONO (-5190 5760);
FORCEPROP 0 LASTPIN (-5200 5700) $PN CB64
J 0
(-5190 5710);
DISPLAY 0.489362 (-5190 5710);
PAINT MONO (-5190 5710);
FORCEPROP 0 LASTPIN (-5200 5650) $PN CB66
J 0
(-5190 5660);
DISPLAY 0.489362 (-5190 5660);
PAINT MONO (-5190 5660);
FORCEPROP 0 LASTPIN (-5200 5600) $PN CB68
J 0
(-5190 5610);
DISPLAY 0.489362 (-5190 5610);
PAINT MONO (-5190 5610);
FORCEPROP 0 LASTPIN (-5200 5550) $PN CB71
J 0
(-5190 5560);
DISPLAY 0.489362 (-5190 5560);
PAINT MONO (-5190 5560);
FORCEPROP 0 LASTPIN (-5200 5500) $PN CB73
J 0
(-5190 5510);
DISPLAY 0.489362 (-5190 5510);
PAINT MONO (-5190 5510);
FORCEPROP 0 LASTPIN (-5200 5450) $PN CC1
J 0
(-5190 5460);
DISPLAY 0.489362 (-5190 5460);
PAINT MONO (-5190 5460);
FORCEPROP 0 LASTPIN (-5200 5400) $PN CC4
J 0
(-5190 5410);
DISPLAY 0.489362 (-5190 5410);
PAINT MONO (-5190 5410);
FORCEPROP 0 LASTPIN (-5200 5350) $PN CC6
J 0
(-5190 5360);
DISPLAY 0.489362 (-5190 5360);
PAINT MONO (-5190 5360);
FORCEPROP 0 LASTPIN (-5200 5300) $PN CC8
J 0
(-5190 5310);
DISPLAY 0.489362 (-5190 5310);
PAINT MONO (-5190 5310);
FORCEPROP 0 LASTPIN (-5200 5250) $PN CC11
J 0
(-5190 5260);
DISPLAY 0.489362 (-5190 5260);
PAINT MONO (-5190 5260);
FORCEPROP 0 LASTPIN (-5200 5200) $PN CC13
J 0
(-5190 5210);
DISPLAY 0.489362 (-5190 5210);
PAINT MONO (-5190 5210);
FORCEPROP 0 LASTPIN (-5200 5150) $PN CC15
J 0
(-5190 5160);
DISPLAY 0.489362 (-5190 5160);
PAINT MONO (-5190 5160);
FORCEPROP 0 LASTPIN (-5200 5100) $PN CC18
J 0
(-5190 5110);
DISPLAY 0.489362 (-5190 5110);
PAINT MONO (-5190 5110);
FORCEPROP 0 LASTPIN (-5200 5050) $PN CC20
J 0
(-5190 5060);
DISPLAY 0.489362 (-5190 5060);
PAINT MONO (-5190 5060);
FORCEPROP 0 LASTPIN (-5200 5000) $PN CC25
J 0
(-5190 5010);
DISPLAY 0.489362 (-5190 5010);
PAINT MONO (-5190 5010);
FORCEPROP 0 LASTPIN (-5200 4950) $PN CC28
J 0
(-5190 4960);
DISPLAY 0.489362 (-5190 4960);
PAINT MONO (-5190 4960);
FORCEPROP 0 LASTPIN (-5200 4900) $PN CC31
J 0
(-5190 4910);
DISPLAY 0.489362 (-5190 4910);
PAINT MONO (-5190 4910);
FORCEPROP 0 LASTPIN (-5200 4850) $PN CC34
J 0
(-5190 4860);
DISPLAY 0.489362 (-5190 4860);
PAINT MONO (-5190 4860);
FORCEPROP 0 LASTPIN (-5200 4800) $PN CC42
J 0
(-5190 4810);
DISPLAY 0.489362 (-5190 4810);
PAINT MONO (-5190 4810);
FORCEPROP 0 LASTPIN (-5200 4750) $PN CC45
J 0
(-5190 4760);
DISPLAY 0.489362 (-5190 4760);
PAINT MONO (-5190 4760);
FORCEPROP 0 LASTPIN (-5200 4700) $PN CC48
J 0
(-5190 4710);
DISPLAY 0.489362 (-5190 4710);
PAINT MONO (-5190 4710);
FORCEPROP 0 LASTPIN (-5200 4650) $PN CC51
J 0
(-5190 4660);
DISPLAY 0.489362 (-5190 4660);
PAINT MONO (-5190 4660);
FORCEPROP 0 LASTPIN (-5200 4600) $PN CC54
J 0
(-5190 4610);
DISPLAY 0.489362 (-5190 4610);
PAINT MONO (-5190 4610);
FORCEPROP 0 LASTPIN (-5200 4550) $PN CC56
J 0
(-5190 4560);
DISPLAY 0.489362 (-5190 4560);
PAINT MONO (-5190 4560);
FORCEPROP 0 LASTPIN (-5200 4500) $PN CC58
J 0
(-5190 4510);
DISPLAY 0.489362 (-5190 4510);
PAINT MONO (-5190 4510);
FORCEPROP 0 LASTPIN (-5200 4450) $PN CC61
J 0
(-5190 4460);
DISPLAY 0.489362 (-5190 4460);
PAINT MONO (-5190 4460);
FORCEPROP 0 LASTPIN (-5200 4400) $PN CC63
J 0
(-5190 4410);
DISPLAY 0.489362 (-5190 4410);
PAINT MONO (-5190 4410);
FORCEPROP 0 LASTPIN (-5200 4350) $PN CC65
J 0
(-5190 4360);
DISPLAY 0.489362 (-5190 4360);
PAINT MONO (-5190 4360);
FORCEPROP 0 LASTPIN (-5200 4300) $PN CC68
J 0
(-5190 4310);
DISPLAY 0.489362 (-5190 4310);
PAINT MONO (-5190 4310);
FORCEPROP 0 LASTPIN (-5200 4250) $PN CC70
J 0
(-5190 4260);
DISPLAY 0.489362 (-5190 4260);
PAINT MONO (-5190 4260);
FORCEPROP 0 LASTPIN (-5200 4200) $PN CC72
J 0
(-5190 4210);
DISPLAY 0.489362 (-5190 4210);
PAINT MONO (-5190 4210);
FORCEPROP 0 LASTPIN (-5200 4150) $PN CC75
J 0
(-5190 4160);
DISPLAY 0.489362 (-5190 4160);
PAINT MONO (-5190 4160);
FORCEPROP 0 LASTPIN (-5200 4100) $PN CD3
J 0
(-5190 4110);
DISPLAY 0.489362 (-5190 4110);
PAINT MONO (-5190 4110);
FORCEPROP 0 LASTPIN (-5200 4050) $PN CD8
J 0
(-5190 4060);
DISPLAY 0.489362 (-5190 4060);
PAINT MONO (-5190 4060);
FORCEPROP 0 LASTPIN (-5200 4000) $PN CD10
J 0
(-5190 4010);
DISPLAY 0.489362 (-5190 4010);
PAINT MONO (-5190 4010);
FORCEPROP 0 LASTPIN (-5200 3950) $PN CD15
J 0
(-5190 3960);
DISPLAY 0.489362 (-5190 3960);
PAINT MONO (-5190 3960);
FORCEPROP 0 LASTPIN (-5200 3900) $PN CD17
J 0
(-5190 3910);
DISPLAY 0.489362 (-5190 3910);
PAINT MONO (-5190 3910);
FORCEPROP 0 LASTPIN (-5200 3850) $PN CD22
J 0
(-5190 3860);
DISPLAY 0.489362 (-5190 3860);
PAINT MONO (-5190 3860);
FORCEPROP 0 LASTPIN (-5200 3800) $PN CD25
J 0
(-5190 3810);
DISPLAY 0.489362 (-5190 3810);
PAINT MONO (-5190 3810);
FORCEPROP 0 LASTPIN (-5200 3750) $PN CD28
J 0
(-5190 3760);
DISPLAY 0.489362 (-5190 3760);
PAINT MONO (-5190 3760);
FORCEPROP 0 LASTPIN (-5200 3700) $PN CD31
J 0
(-5190 3710);
DISPLAY 0.489362 (-5190 3710);
PAINT MONO (-5190 3710);
FORCEPROP 0 LASTPIN (-5200 3650) $PN CD34
J 0
(-5190 3660);
DISPLAY 0.489362 (-5190 3660);
PAINT MONO (-5190 3660);
FORCEPROP 0 LASTPIN (-5200 3600) $PN CD37
J 0
(-5190 3610);
DISPLAY 0.489362 (-5190 3610);
PAINT MONO (-5190 3610);
FORCEPROP 0 LASTPIN (-5200 3550) $PN CD39
J 0
(-5190 3560);
DISPLAY 0.489362 (-5190 3560);
PAINT MONO (-5190 3560);
FORCEPROP 0 LASTPIN (-5200 3500) $PN CD42
J 0
(-5190 3510);
DISPLAY 0.489362 (-5190 3510);
PAINT MONO (-5190 3510);
FORCEPROP 0 LASTPIN (-5200 3450) $PN CD45
J 0
(-5190 3460);
DISPLAY 0.489362 (-5190 3460);
PAINT MONO (-5190 3460);
FORCEPROP 0 LASTPIN (-5200 3400) $PN CD48
J 0
(-5190 3410);
DISPLAY 0.489362 (-5190 3410);
PAINT MONO (-5190 3410);
FORCEPROP 0 LASTPIN (-5200 3350) $PN CD51
J 0
(-5190 3360);
DISPLAY 0.489362 (-5190 3360);
PAINT MONO (-5190 3360);
FORCEPROP 0 LASTPIN (-5200 3300) $PN CD54
J 0
(-5190 3310);
DISPLAY 0.489362 (-5190 3310);
PAINT MONO (-5190 3310);
FORCEPROP 0 LASTPIN (-5200 3250) $PN CD59
J 0
(-5190 3260);
DISPLAY 0.489362 (-5190 3260);
PAINT MONO (-5190 3260);
FORCEPROP 0 LASTPIN (-5200 3200) $PN CD61
J 0
(-5190 3210);
DISPLAY 0.489362 (-5190 3210);
PAINT MONO (-5190 3210);
FORCEPROP 0 LASTPIN (-5200 3150) $PN CD66
J 0
(-5190 3160);
DISPLAY 0.489362 (-5190 3160);
PAINT MONO (-5190 3160);
FORCEPROP 0 LASTPIN (-5200 3100) $PN CD68
J 0
(-5190 3110);
DISPLAY 0.489362 (-5190 3110);
PAINT MONO (-5190 3110);
FORCEPROP 0 LASTPIN (-5200 3050) $PN CD73
J 0
(-5190 3060);
DISPLAY 0.489362 (-5190 3060);
PAINT MONO (-5190 3060);
FORCEPROP 0 LASTPIN (-5200 3000) $PN CE1
J 0
(-5190 3010);
DISPLAY 0.489362 (-5190 3010);
PAINT MONO (-5190 3010);
FORCEPROP 0 LASTPIN (-5200 2950) $PN CE4
J 0
(-5190 2960);
DISPLAY 0.489362 (-5190 2960);
PAINT MONO (-5190 2960);
FORCEPROP 0 LASTPIN (-5200 2900) $PN CE6
J 0
(-5190 2910);
DISPLAY 0.489362 (-5190 2910);
PAINT MONO (-5190 2910);
FORCEPROP 0 LASTPIN (-5200 2850) $PN CE8
J 0
(-5190 2860);
DISPLAY 0.489362 (-5190 2860);
PAINT MONO (-5190 2860);
FORCEPROP 0 LASTPIN (-5200 2800) $PN CE11
J 0
(-5190 2810);
DISPLAY 0.489362 (-5190 2810);
PAINT MONO (-5190 2810);
FORCEPROP 0 LASTPIN (-5200 2750) $PN CE13
J 0
(-5190 2760);
DISPLAY 0.489362 (-5190 2760);
PAINT MONO (-5190 2760);
FORCEPROP 0 LASTPIN (-5200 2700) $PN CE15
J 0
(-5190 2710);
DISPLAY 0.489362 (-5190 2710);
PAINT MONO (-5190 2710);
FORCEPROP 0 LASTPIN (-5200 2650) $PN CE18
J 0
(-5190 2660);
DISPLAY 0.489362 (-5190 2660);
PAINT MONO (-5190 2660);
FORCEPROP 0 LASTPIN (-5200 2600) $PN CE20
J 0
(-5190 2610);
DISPLAY 0.489362 (-5190 2610);
PAINT MONO (-5190 2610);
FORCEPROP 0 LASTPIN (-5200 2550) $PN CE22
J 0
(-5190 2560);
DISPLAY 0.489362 (-5190 2560);
PAINT MONO (-5190 2560);
FORCEPROP 0 LASTPIN (-5200 2500) $PN CE25
J 0
(-5190 2510);
DISPLAY 0.489362 (-5190 2510);
PAINT MONO (-5190 2510);
FORCEPROP 0 LASTPIN (-5200 2450) $PN CE28
J 0
(-5190 2460);
DISPLAY 0.489362 (-5190 2460);
PAINT MONO (-5190 2460);
FORCEPROP 0 LASTPIN (-5200 2400) $PN CE31
J 0
(-5190 2410);
DISPLAY 0.489362 (-5190 2410);
PAINT MONO (-5190 2410);
FORCEPROP 0 LASTPIN (-5200 2350) $PN CE34
J 0
(-5190 2360);
DISPLAY 0.489362 (-5190 2360);
PAINT MONO (-5190 2360);
FORCEPROP 0 LASTPIN (-5200 2300) $PN CE35
J 0
(-5190 2310);
DISPLAY 0.489362 (-5190 2310);
PAINT MONO (-5190 2310);
FORCEPROP 0 LASTPIN (-5200 2250) $PN CE36
J 0
(-5190 2260);
DISPLAY 0.489362 (-5190 2260);
PAINT MONO (-5190 2260);
FORCEPROP 0 LASTPIN (-5200 2200) $PN CE40
J 0
(-5190 2210);
DISPLAY 0.489362 (-5190 2210);
PAINT MONO (-5190 2210);
FORCEPROP 0 LASTPIN (-5200 2150) $PN CE41
J 0
(-5190 2160);
DISPLAY 0.489362 (-5190 2160);
PAINT MONO (-5190 2160);
FORCEPROP 0 LASTPIN (-5200 2100) $PN CE42
J 0
(-5190 2110);
DISPLAY 0.489362 (-5190 2110);
PAINT MONO (-5190 2110);
FORCEPROP 0 LASTPIN (-5200 2050) $PN CE45
J 0
(-5190 2060);
DISPLAY 0.489362 (-5190 2060);
PAINT MONO (-5190 2060);
FORCEPROP 0 LASTPIN (-5200 2000) $PN CE48
J 0
(-5190 2010);
DISPLAY 0.489362 (-5190 2010);
PAINT MONO (-5190 2010);
FORCEPROP 0 LASTPIN (-5200 1950) $PN CE51
J 0
(-5190 1960);
DISPLAY 0.489362 (-5190 1960);
PAINT MONO (-5190 1960);
FORCEPROP 0 LASTPIN (-5200 1900) $PN CE54
J 0
(-5190 1910);
DISPLAY 0.489362 (-5190 1910);
PAINT MONO (-5190 1910);
FORCEPROP 0 LASTPIN (-5200 1850) $PN CE56
J 0
(-5190 1860);
DISPLAY 0.489362 (-5190 1860);
PAINT MONO (-5190 1860);
FORCEPROP 0 LASTPIN (-5200 1800) $PN CE58
J 0
(-5190 1810);
DISPLAY 0.489362 (-5190 1810);
PAINT MONO (-5190 1810);
FORCEPROP 0 LASTPIN (-5200 1750) $PN CE61
J 0
(-5190 1760);
DISPLAY 0.489362 (-5190 1760);
PAINT MONO (-5190 1760);
FORCEPROP 0 LASTPIN (-5200 1700) $PN CE63
J 0
(-5190 1710);
DISPLAY 0.489362 (-5190 1710);
PAINT MONO (-5190 1710);
FORCEPROP 0 LASTPIN (-5200 1650) $PN CE65
J 0
(-5190 1660);
DISPLAY 0.489362 (-5190 1660);
PAINT MONO (-5190 1660);
FORCEPROP 0 LASTPIN (-5200 1600) $PN CE68
J 0
(-5190 1610);
DISPLAY 0.489362 (-5190 1610);
PAINT MONO (-5190 1610);
FORCEPROP 0 LASTPIN (-5200 1550) $PN CE70
J 0
(-5190 1560);
DISPLAY 0.489362 (-5190 1560);
PAINT MONO (-5190 1560);
FORCEPROP 0 LASTPIN (-5200 1500) $PN CE72
J 0
(-5190 1510);
DISPLAY 0.489362 (-5190 1510);
PAINT MONO (-5190 1510);
FORCEPROP 0 LASTPIN (-5200 1450) $PN CE75
J 0
(-5190 1460);
DISPLAY 0.489362 (-5190 1460);
PAINT MONO (-5190 1460);
FORCEPROP 0 LASTPIN (-5200 1400) $PN CF3
J 0
(-5190 1410);
DISPLAY 0.489362 (-5190 1410);
PAINT MONO (-5190 1410);
FORCEPROP 0 LASTPIN (-5200 1350) $PN CF5
J 0
(-5190 1360);
DISPLAY 0.489362 (-5190 1360);
PAINT MONO (-5190 1360);
FORCEPROP 0 LASTPIN (-5200 1300) $PN CF8
J 0
(-5190 1310);
DISPLAY 0.489362 (-5190 1310);
PAINT MONO (-5190 1310);
FORCEPROP 0 LASTPIN (-5200 1250) $PN CF10
J 0
(-5190 1260);
DISPLAY 0.489362 (-5190 1260);
PAINT MONO (-5190 1260);
FORCEPROP 0 LASTPIN (-5200 1200) $PN CF12
J 0
(-5190 1210);
DISPLAY 0.489362 (-5190 1210);
PAINT MONO (-5190 1210);
FORCEPROP 0 LASTPIN (-5200 1150) $PN CF15
J 0
(-5190 1160);
DISPLAY 0.489362 (-5190 1160);
PAINT MONO (-5190 1160);
FORCEPROP 0 LASTPIN (-5200 1100) $PN CF17
J 0
(-5190 1110);
DISPLAY 0.489362 (-5190 1110);
PAINT MONO (-5190 1110);
FORCEPROP 0 LASTPIN (-5200 1050) $PN CF19
J 0
(-5190 1060);
DISPLAY 0.489362 (-5190 1060);
PAINT MONO (-5190 1060);
FORCEPROP 0 LASTPIN (-5200 1000) $PN CF23
J 0
(-5190 1010);
DISPLAY 0.489362 (-5190 1010);
PAINT MONO (-5190 1010);
FORCEPROP 0 LASTPIN (-5200 950) $PN CF24
J 0
(-5190 960);
DISPLAY 0.489362 (-5190 960);
PAINT MONO (-5190 960);
FORCEPROP 0 LASTPIN (-5200 900) $PN CF25
J 0
(-5190 910);
DISPLAY 0.489362 (-5190 910);
PAINT MONO (-5190 910);
FORCEPROP 0 LASTPIN (-5200 850) $PN CF26
J 0
(-5190 860);
DISPLAY 0.489362 (-5190 860);
PAINT MONO (-5190 860);
FORCEPROP 0 LASTPIN (-5200 800) $PN CF27
J 0
(-5190 810);
DISPLAY 0.489362 (-5190 810);
PAINT MONO (-5190 810);
FORCEPROP 0 LASTPIN (-5200 750) $PN CF28
J 0
(-5190 760);
DISPLAY 0.489362 (-5190 760);
PAINT MONO (-5190 760);
FORCEPROP 0 LASTPIN (-5200 700) $PN CF29
J 0
(-5190 710);
DISPLAY 0.489362 (-5190 710);
PAINT MONO (-5190 710);
FORCEPROP 0 LASTPIN (-5200 650) $PN CF30
J 0
(-5190 660);
DISPLAY 0.489362 (-5190 660);
PAINT MONO (-5190 660);
FORCEPROP 0 LASTPIN (-5200 600) $PN CF31
J 0
(-5190 610);
DISPLAY 0.489362 (-5190 610);
PAINT MONO (-5190 610);
FORCEPROP 0 LASTPIN (-5200 550) $PN CF32
J 0
(-5190 560);
DISPLAY 0.489362 (-5190 560);
PAINT MONO (-5190 560);
FORCEPROP 0 LASTPIN (-5200 500) $PN CF33
J 0
(-5190 510);
DISPLAY 0.489362 (-5190 510);
PAINT MONO (-5190 510);
FORCEPROP 2 LAST PART_TYPE SMLF
J 0
(-6150 6700);
DISPLAY 1.021277 (-6150 6700);
FORCEPROP 1 LAST MATERIAL IO
J 0
(-6145 6532);
DISPLAY 0.489362 (-6145 6532);
PAINT SKYBLUE (-6145 6532);
FORCEPROP 2 LAST VALUE SOCKET6096_13568-001
J 0
(-6150 6575);
DISPLAY 0.489362 (-6150 6575);
PAINT SKYBLUE (-6150 6575);
FORCEPROP 1 LAST NEEDS_NO_SIZE TRUE
J 0
(-5750 3450);
DISPLAY 0.723404 (-5750 3450);
PAINT GREEN (-5750 3450);
DISPLAY INVISIBLE (-5750 3450);
FORCEPROP 1 LAST CDS_LMAN_SYM_OUTLINE -400,3050,400,-3050
J 0
(-5750 3450);
DISPLAY 0.468085 (-5750 3450);
PAINT GREEN (-5750 3450);
DISPLAY INVISIBLE (-5750 3450);
FORCEPROP 2 LAST CDS_LIB pure_quanta
J 0
(-5750 3450);
DISPLAY INVISIBLE (-5750 3450);
FORCEPROP 1 LAST PATH I14
J 0
(-5750 3450);
DISPLAY 0.723404 (-5750 3450);
PAINT GREEN (-5750 3450);
DISPLAY INVISIBLE (-5750 3450);
FORCEPROP 1 LAST PART_NUMBER DGA^6000030
J 0
(-6145 6659);
DISPLAY 0.489362 (-6145 6659);
PAINT SKYBLUE (-6145 6659);
DISPLAY INVISIBLE (-6145 6659);
FORCEADD GENOA_SP5..38
(-3675 3425);
FORCEPROP 1 LAST LOCATION U25
J 0
(-4070 6600);
DISPLAY 0.489362 (-4070 6600);
PAINT SKYBLUE (-4070 6600);
FORCEPROP 0 LAST $SEC 38
J 0
(-4050 6825);
DISPLAY 0.680851 (-4050 6825);
PAINT MONO (-4050 6825);
DISPLAY INVISIBLE (-4050 6825);
FORCEPROP 0 LAST CDS_SEC 38
J 0
(-4300 6650);
DISPLAY 1.021277 (-4300 6650);
DISPLAY INVISIBLE (-4300 6650);
FORCEPROP 0 LASTPIN (-4225 6275) $PN CF34
J 2
(-4235 6285);
DISPLAY 0.489362 (-4235 6285);
PAINT MONO (-4235 6285);
FORCEPROP 0 LASTPIN (-4225 6225) $PN CF37
J 2
(-4235 6235);
DISPLAY 0.489362 (-4235 6235);
PAINT MONO (-4235 6235);
FORCEPROP 0 LASTPIN (-4225 6175) $PN CF39
J 2
(-4235 6185);
DISPLAY 0.489362 (-4235 6185);
PAINT MONO (-4235 6185);
FORCEPROP 0 LASTPIN (-4225 6125) $PN CF42
J 2
(-4235 6135);
DISPLAY 0.489362 (-4235 6135);
PAINT MONO (-4235 6135);
FORCEPROP 0 LASTPIN (-4225 6075) $PN CF43
J 2
(-4235 6085);
DISPLAY 0.489362 (-4235 6085);
PAINT MONO (-4235 6085);
FORCEPROP 0 LASTPIN (-4225 6025) $PN CF44
J 2
(-4235 6035);
DISPLAY 0.489362 (-4235 6035);
PAINT MONO (-4235 6035);
FORCEPROP 0 LASTPIN (-4225 5975) $PN CF45
J 2
(-4235 5985);
DISPLAY 0.489362 (-4235 5985);
PAINT MONO (-4235 5985);
FORCEPROP 0 LASTPIN (-4225 5925) $PN CF47
J 2
(-4235 5935);
DISPLAY 0.489362 (-4235 5935);
PAINT MONO (-4235 5935);
FORCEPROP 0 LASTPIN (-4225 5875) $PN CF48
J 2
(-4235 5885);
DISPLAY 0.489362 (-4235 5885);
PAINT MONO (-4235 5885);
FORCEPROP 0 LASTPIN (-4225 5825) $PN CF49
J 2
(-4235 5835);
DISPLAY 0.489362 (-4235 5835);
PAINT MONO (-4235 5835);
FORCEPROP 0 LASTPIN (-4225 5775) $PN CF50
J 2
(-4235 5785);
DISPLAY 0.489362 (-4235 5785);
PAINT MONO (-4235 5785);
FORCEPROP 0 LASTPIN (-4225 5725) $PN CF51
J 2
(-4235 5735);
DISPLAY 0.489362 (-4235 5735);
PAINT MONO (-4235 5735);
FORCEPROP 0 LASTPIN (-4225 5675) $PN CF52
J 2
(-4235 5685);
DISPLAY 0.489362 (-4235 5685);
PAINT MONO (-4235 5685);
FORCEPROP 0 LASTPIN (-4225 5625) $PN CF53
J 2
(-4235 5635);
DISPLAY 0.489362 (-4235 5635);
PAINT MONO (-4235 5635);
FORCEPROP 0 LASTPIN (-4225 5575) $PN CF57
J 2
(-4235 5585);
DISPLAY 0.489362 (-4235 5585);
PAINT MONO (-4235 5585);
FORCEPROP 0 LASTPIN (-4225 5525) $PN CF59
J 2
(-4235 5535);
DISPLAY 0.489362 (-4235 5535);
PAINT MONO (-4235 5535);
FORCEPROP 0 LASTPIN (-4225 5475) $PN CF61
J 2
(-4235 5485);
DISPLAY 0.489362 (-4235 5485);
PAINT MONO (-4235 5485);
FORCEPROP 0 LASTPIN (-4225 5425) $PN CF64
J 2
(-4235 5435);
DISPLAY 0.489362 (-4235 5435);
PAINT MONO (-4235 5435);
FORCEPROP 0 LASTPIN (-4225 5375) $PN CF66
J 2
(-4235 5385);
DISPLAY 0.489362 (-4235 5385);
PAINT MONO (-4235 5385);
FORCEPROP 0 LASTPIN (-4225 5325) $PN CF68
J 2
(-4235 5335);
DISPLAY 0.489362 (-4235 5335);
PAINT MONO (-4235 5335);
FORCEPROP 0 LASTPIN (-4225 5275) $PN CF71
J 2
(-4235 5285);
DISPLAY 0.489362 (-4235 5285);
PAINT MONO (-4235 5285);
FORCEPROP 0 LASTPIN (-4225 5225) $PN CF73
J 2
(-4235 5235);
DISPLAY 0.489362 (-4235 5235);
PAINT MONO (-4235 5235);
FORCEPROP 0 LASTPIN (-4225 5175) $PN CG1
J 2
(-4235 5185);
DISPLAY 0.489362 (-4235 5185);
PAINT MONO (-4235 5185);
FORCEPROP 0 LASTPIN (-4225 5125) $PN CG6
J 2
(-4235 5135);
DISPLAY 0.489362 (-4235 5135);
PAINT MONO (-4235 5135);
FORCEPROP 0 LASTPIN (-4225 5075) $PN CG8
J 2
(-4235 5085);
DISPLAY 0.489362 (-4235 5085);
PAINT MONO (-4235 5085);
FORCEPROP 0 LASTPIN (-4225 5025) $PN CG13
J 2
(-4235 5035);
DISPLAY 0.489362 (-4235 5035);
PAINT MONO (-4235 5035);
FORCEPROP 0 LASTPIN (-4225 4975) $PN CG15
J 2
(-4235 4985);
DISPLAY 0.489362 (-4235 4985);
PAINT MONO (-4235 4985);
FORCEPROP 0 LASTPIN (-4225 4925) $PN CG20
J 2
(-4235 4935);
DISPLAY 0.489362 (-4235 4935);
PAINT MONO (-4235 4935);
FORCEPROP 0 LASTPIN (-4225 4875) $PN CG22
J 2
(-4235 4885);
DISPLAY 0.489362 (-4235 4885);
PAINT MONO (-4235 4885);
FORCEPROP 0 LASTPIN (-4225 4825) $PN CG25
J 2
(-4235 4835);
DISPLAY 0.489362 (-4235 4835);
PAINT MONO (-4235 4835);
FORCEPROP 0 LASTPIN (-4225 4775) $PN CG28
J 2
(-4235 4785);
DISPLAY 0.489362 (-4235 4785);
PAINT MONO (-4235 4785);
FORCEPROP 0 LASTPIN (-4225 4725) $PN CG31
J 2
(-4235 4735);
DISPLAY 0.489362 (-4235 4735);
PAINT MONO (-4235 4735);
FORCEPROP 0 LASTPIN (-4225 4675) $PN CG34
J 2
(-4235 4685);
DISPLAY 0.489362 (-4235 4685);
PAINT MONO (-4235 4685);
FORCEPROP 0 LASTPIN (-4225 4625) $PN CG45
J 2
(-4235 4635);
DISPLAY 0.489362 (-4235 4635);
PAINT MONO (-4235 4635);
FORCEPROP 0 LASTPIN (-4225 4575) $PN CG48
J 2
(-4235 4585);
DISPLAY 0.489362 (-4235 4585);
PAINT MONO (-4235 4585);
FORCEPROP 0 LASTPIN (-4225 4525) $PN CG51
J 2
(-4235 4535);
DISPLAY 0.489362 (-4235 4535);
PAINT MONO (-4235 4535);
FORCEPROP 0 LASTPIN (-4225 4475) $PN CG54
J 2
(-4235 4485);
DISPLAY 0.489362 (-4235 4485);
PAINT MONO (-4235 4485);
FORCEPROP 0 LASTPIN (-4225 4425) $PN CG56
J 2
(-4235 4435);
DISPLAY 0.489362 (-4235 4435);
PAINT MONO (-4235 4435);
FORCEPROP 0 LASTPIN (-4225 4375) $PN CG61
J 2
(-4235 4385);
DISPLAY 0.489362 (-4235 4385);
PAINT MONO (-4235 4385);
FORCEPROP 0 LASTPIN (-4225 4325) $PN CG63
J 2
(-4235 4335);
DISPLAY 0.489362 (-4235 4335);
PAINT MONO (-4235 4335);
FORCEPROP 0 LASTPIN (-4225 4275) $PN CG68
J 2
(-4235 4285);
DISPLAY 0.489362 (-4235 4285);
PAINT MONO (-4235 4285);
FORCEPROP 0 LASTPIN (-4225 4225) $PN CG70
J 2
(-4235 4235);
DISPLAY 0.489362 (-4235 4235);
PAINT MONO (-4235 4235);
FORCEPROP 0 LASTPIN (-4225 4175) $PN CG75
J 2
(-4235 4185);
DISPLAY 0.489362 (-4235 4185);
PAINT MONO (-4235 4185);
FORCEPROP 0 LASTPIN (-4225 4125) $PN CH3
J 2
(-4235 4135);
DISPLAY 0.489362 (-4235 4135);
PAINT MONO (-4235 4135);
FORCEPROP 0 LASTPIN (-4225 4075) $PN CH5
J 2
(-4235 4085);
DISPLAY 0.489362 (-4235 4085);
PAINT MONO (-4235 4085);
FORCEPROP 0 LASTPIN (-4225 4025) $PN CH8
J 2
(-4235 4035);
DISPLAY 0.489362 (-4235 4035);
PAINT MONO (-4235 4035);
FORCEPROP 0 LASTPIN (-4225 3975) $PN CH10
J 2
(-4235 3985);
DISPLAY 0.489362 (-4235 3985);
PAINT MONO (-4235 3985);
FORCEPROP 0 LASTPIN (-4225 3925) $PN CH12
J 2
(-4235 3935);
DISPLAY 0.489362 (-4235 3935);
PAINT MONO (-4235 3935);
FORCEPROP 0 LASTPIN (-4225 3875) $PN CH15
J 2
(-4235 3885);
DISPLAY 0.489362 (-4235 3885);
PAINT MONO (-4235 3885);
FORCEPROP 0 LASTPIN (-4225 3825) $PN CH17
J 2
(-4235 3835);
DISPLAY 0.489362 (-4235 3835);
PAINT MONO (-4235 3835);
FORCEPROP 0 LASTPIN (-4225 3775) $PN CH19
J 2
(-4235 3785);
DISPLAY 0.489362 (-4235 3785);
PAINT MONO (-4235 3785);
FORCEPROP 0 LASTPIN (-4225 3725) $PN CH22
J 2
(-4235 3735);
DISPLAY 0.489362 (-4235 3735);
PAINT MONO (-4235 3735);
FORCEPROP 0 LASTPIN (-4225 3675) $PN CH25
J 2
(-4235 3685);
DISPLAY 0.489362 (-4235 3685);
PAINT MONO (-4235 3685);
FORCEPROP 0 LASTPIN (-4225 3625) $PN CH28
J 2
(-4235 3635);
DISPLAY 0.489362 (-4235 3635);
PAINT MONO (-4235 3635);
FORCEPROP 0 LASTPIN (-4225 3575) $PN CH31
J 2
(-4235 3585);
DISPLAY 0.489362 (-4235 3585);
PAINT MONO (-4235 3585);
FORCEPROP 0 LASTPIN (-4225 3525) $PN CH34
J 2
(-4235 3535);
DISPLAY 0.489362 (-4235 3535);
PAINT MONO (-4235 3535);
FORCEPROP 0 LASTPIN (-4225 3475) $PN CH37
J 2
(-4235 3485);
DISPLAY 0.489362 (-4235 3485);
PAINT MONO (-4235 3485);
FORCEPROP 0 LASTPIN (-4225 3425) $PN CH39
J 2
(-4235 3435);
DISPLAY 0.489362 (-4235 3435);
PAINT MONO (-4235 3435);
FORCEPROP 0 LASTPIN (-4225 3375) $PN CH42
J 2
(-4235 3385);
DISPLAY 0.489362 (-4235 3385);
PAINT MONO (-4235 3385);
FORCEPROP 0 LASTPIN (-4225 3325) $PN CH45
J 2
(-4235 3335);
DISPLAY 0.489362 (-4235 3335);
PAINT MONO (-4235 3335);
FORCEPROP 0 LASTPIN (-4225 3275) $PN CH48
J 2
(-4235 3285);
DISPLAY 0.489362 (-4235 3285);
PAINT MONO (-4235 3285);
FORCEPROP 0 LASTPIN (-4225 3225) $PN CH51
J 2
(-4235 3235);
DISPLAY 0.489362 (-4235 3235);
PAINT MONO (-4235 3235);
FORCEPROP 0 LASTPIN (-4225 3175) $PN CH54
J 2
(-4235 3185);
DISPLAY 0.489362 (-4235 3185);
PAINT MONO (-4235 3185);
FORCEPROP 0 LASTPIN (-4225 3125) $PN CH57
J 2
(-4235 3135);
DISPLAY 0.489362 (-4235 3135);
PAINT MONO (-4235 3135);
FORCEPROP 0 LASTPIN (-4225 3075) $PN CH59
J 2
(-4235 3085);
DISPLAY 0.489362 (-4235 3085);
PAINT MONO (-4235 3085);
FORCEPROP 0 LASTPIN (-4225 3025) $PN CH61
J 2
(-4235 3035);
DISPLAY 0.489362 (-4235 3035);
PAINT MONO (-4235 3035);
FORCEPROP 0 LASTPIN (-4225 2975) $PN CH64
J 2
(-4235 2985);
DISPLAY 0.489362 (-4235 2985);
PAINT MONO (-4235 2985);
FORCEPROP 0 LASTPIN (-4225 2925) $PN CH66
J 2
(-4235 2935);
DISPLAY 0.489362 (-4235 2935);
PAINT MONO (-4235 2935);
FORCEPROP 0 LASTPIN (-4225 2875) $PN CH68
J 2
(-4235 2885);
DISPLAY 0.489362 (-4235 2885);
PAINT MONO (-4235 2885);
FORCEPROP 0 LASTPIN (-4225 2825) $PN CH71
J 2
(-4235 2835);
DISPLAY 0.489362 (-4235 2835);
PAINT MONO (-4235 2835);
FORCEPROP 0 LASTPIN (-4225 2775) $PN CH73
J 2
(-4235 2785);
DISPLAY 0.489362 (-4235 2785);
PAINT MONO (-4235 2785);
FORCEPROP 0 LASTPIN (-4225 2725) $PN CJ1
J 2
(-4235 2735);
DISPLAY 0.489362 (-4235 2735);
PAINT MONO (-4235 2735);
FORCEPROP 0 LASTPIN (-4225 2675) $PN CJ4
J 2
(-4235 2685);
DISPLAY 0.489362 (-4235 2685);
PAINT MONO (-4235 2685);
FORCEPROP 0 LASTPIN (-4225 2625) $PN CJ6
J 2
(-4235 2635);
DISPLAY 0.489362 (-4235 2635);
PAINT MONO (-4235 2635);
FORCEPROP 0 LASTPIN (-4225 2575) $PN CJ8
J 2
(-4235 2585);
DISPLAY 0.489362 (-4235 2585);
PAINT MONO (-4235 2585);
FORCEPROP 0 LASTPIN (-4225 2525) $PN CJ11
J 2
(-4235 2535);
DISPLAY 0.489362 (-4235 2535);
PAINT MONO (-4235 2535);
FORCEPROP 0 LASTPIN (-4225 2475) $PN CJ13
J 2
(-4235 2485);
DISPLAY 0.489362 (-4235 2485);
PAINT MONO (-4235 2485);
FORCEPROP 0 LASTPIN (-4225 2425) $PN CJ15
J 2
(-4235 2435);
DISPLAY 0.489362 (-4235 2435);
PAINT MONO (-4235 2435);
FORCEPROP 0 LASTPIN (-4225 2375) $PN CJ18
J 2
(-4235 2385);
DISPLAY 0.489362 (-4235 2385);
PAINT MONO (-4235 2385);
FORCEPROP 0 LASTPIN (-4225 2325) $PN CJ20
J 2
(-4235 2335);
DISPLAY 0.489362 (-4235 2335);
PAINT MONO (-4235 2335);
FORCEPROP 0 LASTPIN (-4225 2275) $PN CJ23
J 2
(-4235 2285);
DISPLAY 0.489362 (-4235 2285);
PAINT MONO (-4235 2285);
FORCEPROP 0 LASTPIN (-4225 2225) $PN CJ31
J 2
(-4235 2235);
DISPLAY 0.489362 (-4235 2235);
PAINT MONO (-4235 2235);
FORCEPROP 0 LASTPIN (-4225 2175) $PN CJ34
J 2
(-4235 2185);
DISPLAY 0.489362 (-4235 2185);
PAINT MONO (-4235 2185);
FORCEPROP 0 LASTPIN (-4225 2125) $PN CJ35
J 2
(-4235 2135);
DISPLAY 0.489362 (-4235 2135);
PAINT MONO (-4235 2135);
FORCEPROP 0 LASTPIN (-4225 2075) $PN CJ36
J 2
(-4235 2085);
DISPLAY 0.489362 (-4235 2085);
PAINT MONO (-4235 2085);
FORCEPROP 0 LASTPIN (-4225 2025) $PN CJ40
J 2
(-4235 2035);
DISPLAY 0.489362 (-4235 2035);
PAINT MONO (-4235 2035);
FORCEPROP 0 LASTPIN (-4225 1975) $PN CJ41
J 2
(-4235 1985);
DISPLAY 0.489362 (-4235 1985);
PAINT MONO (-4235 1985);
FORCEPROP 0 LASTPIN (-4225 1925) $PN CJ42
J 2
(-4235 1935);
DISPLAY 0.489362 (-4235 1935);
PAINT MONO (-4235 1935);
FORCEPROP 0 LASTPIN (-4225 1875) $PN CJ45
J 2
(-4235 1885);
DISPLAY 0.489362 (-4235 1885);
PAINT MONO (-4235 1885);
FORCEPROP 0 LASTPIN (-4225 1825) $PN CJ56
J 2
(-4235 1835);
DISPLAY 0.489362 (-4235 1835);
PAINT MONO (-4235 1835);
FORCEPROP 0 LASTPIN (-4225 1775) $PN CJ58
J 2
(-4235 1785);
DISPLAY 0.489362 (-4235 1785);
PAINT MONO (-4235 1785);
FORCEPROP 0 LASTPIN (-4225 1725) $PN CJ61
J 2
(-4235 1735);
DISPLAY 0.489362 (-4235 1735);
PAINT MONO (-4235 1735);
FORCEPROP 0 LASTPIN (-4225 1675) $PN CJ63
J 2
(-4235 1685);
DISPLAY 0.489362 (-4235 1685);
PAINT MONO (-4235 1685);
FORCEPROP 0 LASTPIN (-4225 1625) $PN CJ65
J 2
(-4235 1635);
DISPLAY 0.489362 (-4235 1635);
PAINT MONO (-4235 1635);
FORCEPROP 0 LASTPIN (-4225 1575) $PN CJ68
J 2
(-4235 1585);
DISPLAY 0.489362 (-4235 1585);
PAINT MONO (-4235 1585);
FORCEPROP 0 LASTPIN (-4225 1525) $PN CJ70
J 2
(-4235 1535);
DISPLAY 0.489362 (-4235 1535);
PAINT MONO (-4235 1535);
FORCEPROP 0 LASTPIN (-4225 1475) $PN CJ72
J 2
(-4235 1485);
DISPLAY 0.489362 (-4235 1485);
PAINT MONO (-4235 1485);
FORCEPROP 0 LASTPIN (-4225 1425) $PN CJ75
J 2
(-4235 1435);
DISPLAY 0.489362 (-4235 1435);
PAINT MONO (-4235 1435);
FORCEPROP 0 LASTPIN (-4225 1375) $PN CK3
J 2
(-4235 1385);
DISPLAY 0.489362 (-4235 1385);
PAINT MONO (-4235 1385);
FORCEPROP 0 LASTPIN (-4225 1325) $PN CK8
J 2
(-4235 1335);
DISPLAY 0.489362 (-4235 1335);
PAINT MONO (-4235 1335);
FORCEPROP 0 LASTPIN (-4225 1275) $PN CK15
J 2
(-4235 1285);
DISPLAY 0.489362 (-4235 1285);
PAINT MONO (-4235 1285);
FORCEPROP 0 LASTPIN (-4225 1225) $PN CK17
J 2
(-4235 1235);
DISPLAY 0.489362 (-4235 1235);
PAINT MONO (-4235 1235);
FORCEPROP 0 LASTPIN (-4225 1175) $PN CK22
J 2
(-4235 1185);
DISPLAY 0.489362 (-4235 1185);
PAINT MONO (-4235 1185);
FORCEPROP 0 LASTPIN (-4225 1125) $PN CK23
J 2
(-4235 1135);
DISPLAY 0.489362 (-4235 1135);
PAINT MONO (-4235 1135);
FORCEPROP 0 LASTPIN (-4225 1075) $PN CK24
J 2
(-4235 1085);
DISPLAY 0.489362 (-4235 1085);
PAINT MONO (-4235 1085);
FORCEPROP 0 LASTPIN (-4225 1025) $PN CK25
J 2
(-4235 1035);
DISPLAY 0.489362 (-4235 1035);
PAINT MONO (-4235 1035);
FORCEPROP 0 LASTPIN (-4225 975) $PN CK26
J 2
(-4235 985);
DISPLAY 0.489362 (-4235 985);
PAINT MONO (-4235 985);
FORCEPROP 0 LASTPIN (-4225 925) $PN CK27
J 2
(-4235 935);
DISPLAY 0.489362 (-4235 935);
PAINT MONO (-4235 935);
FORCEPROP 0 LASTPIN (-4225 875) $PN CK28
J 2
(-4235 885);
DISPLAY 0.489362 (-4235 885);
PAINT MONO (-4235 885);
FORCEPROP 0 LASTPIN (-4225 825) $PN CK32
J 2
(-4235 835);
DISPLAY 0.489362 (-4235 835);
PAINT MONO (-4235 835);
FORCEPROP 0 LASTPIN (-4225 775) $PN CK33
J 2
(-4235 785);
DISPLAY 0.489362 (-4235 785);
PAINT MONO (-4235 785);
FORCEPROP 0 LASTPIN (-4225 725) $PN CK34
J 2
(-4235 735);
DISPLAY 0.489362 (-4235 735);
PAINT MONO (-4235 735);
FORCEPROP 0 LASTPIN (-4225 675) $PN CK37
J 2
(-4235 685);
DISPLAY 0.489362 (-4235 685);
PAINT MONO (-4235 685);
FORCEPROP 0 LASTPIN (-4225 625) $PN CK39
J 2
(-4235 635);
DISPLAY 0.489362 (-4235 635);
PAINT MONO (-4235 635);
FORCEPROP 0 LASTPIN (-4225 575) $PN CK42
J 2
(-4235 585);
DISPLAY 0.489362 (-4235 585);
PAINT MONO (-4235 585);
FORCEPROP 0 LASTPIN (-3125 6375) $PN CK43
J 0
(-3115 6385);
DISPLAY 0.489362 (-3115 6385);
PAINT MONO (-3115 6385);
FORCEPROP 0 LASTPIN (-3125 6325) $PN CK44
J 0
(-3115 6335);
DISPLAY 0.489362 (-3115 6335);
PAINT MONO (-3115 6335);
FORCEPROP 0 LASTPIN (-3125 6275) $PN CK45
J 0
(-3115 6285);
DISPLAY 0.489362 (-3115 6285);
PAINT MONO (-3115 6285);
FORCEPROP 0 LASTPIN (-3125 6225) $PN CK48
J 0
(-3115 6235);
DISPLAY 0.489362 (-3115 6235);
PAINT MONO (-3115 6235);
FORCEPROP 0 LASTPIN (-3125 6175) $PN CK49
J 0
(-3115 6185);
DISPLAY 0.489362 (-3115 6185);
PAINT MONO (-3115 6185);
FORCEPROP 0 LASTPIN (-3125 6125) $PN CK50
J 0
(-3115 6135);
DISPLAY 0.489362 (-3115 6135);
PAINT MONO (-3115 6135);
FORCEPROP 0 LASTPIN (-3125 6075) $PN CK51
J 0
(-3115 6085);
DISPLAY 0.489362 (-3115 6085);
PAINT MONO (-3115 6085);
FORCEPROP 0 LASTPIN (-3125 6025) $PN CK52
J 0
(-3115 6035);
DISPLAY 0.489362 (-3115 6035);
PAINT MONO (-3115 6035);
FORCEPROP 0 LASTPIN (-3125 5975) $PN CK53
J 0
(-3115 5985);
DISPLAY 0.489362 (-3115 5985);
PAINT MONO (-3115 5985);
FORCEPROP 0 LASTPIN (-3125 5925) $PN CK54
J 0
(-3115 5935);
DISPLAY 0.489362 (-3115 5935);
PAINT MONO (-3115 5935);
FORCEPROP 0 LASTPIN (-3125 5875) $PN CK59
J 0
(-3115 5885);
DISPLAY 0.489362 (-3115 5885);
PAINT MONO (-3115 5885);
FORCEPROP 0 LASTPIN (-3125 5825) $PN CK61
J 0
(-3115 5835);
DISPLAY 0.489362 (-3115 5835);
PAINT MONO (-3115 5835);
FORCEPROP 0 LASTPIN (-3125 5775) $PN CK66
J 0
(-3115 5785);
DISPLAY 0.489362 (-3115 5785);
PAINT MONO (-3115 5785);
FORCEPROP 0 LASTPIN (-3125 5725) $PN CK68
J 0
(-3115 5735);
DISPLAY 0.489362 (-3115 5735);
PAINT MONO (-3115 5735);
FORCEPROP 0 LASTPIN (-3125 5675) $PN CK73
J 0
(-3115 5685);
DISPLAY 0.489362 (-3115 5685);
PAINT MONO (-3115 5685);
FORCEPROP 0 LASTPIN (-3125 5625) $PN CL1
J 0
(-3115 5635);
DISPLAY 0.489362 (-3115 5635);
PAINT MONO (-3115 5635);
FORCEPROP 0 LASTPIN (-3125 5575) $PN CL4
J 0
(-3115 5585);
DISPLAY 0.489362 (-3115 5585);
PAINT MONO (-3115 5585);
FORCEPROP 0 LASTPIN (-3125 5525) $PN CL6
J 0
(-3115 5535);
DISPLAY 0.489362 (-3115 5535);
PAINT MONO (-3115 5535);
FORCEPROP 0 LASTPIN (-3125 5475) $PN CL8
J 0
(-3115 5485);
DISPLAY 0.489362 (-3115 5485);
PAINT MONO (-3115 5485);
FORCEPROP 0 LASTPIN (-3125 5425) $PN CL11
J 0
(-3115 5435);
DISPLAY 0.489362 (-3115 5435);
PAINT MONO (-3115 5435);
FORCEPROP 0 LASTPIN (-3125 5375) $PN CL13
J 0
(-3115 5385);
DISPLAY 0.489362 (-3115 5385);
PAINT MONO (-3115 5385);
FORCEPROP 0 LASTPIN (-3125 5325) $PN CL15
J 0
(-3115 5335);
DISPLAY 0.489362 (-3115 5335);
PAINT MONO (-3115 5335);
FORCEPROP 0 LASTPIN (-3125 5275) $PN CL18
J 0
(-3115 5285);
DISPLAY 0.489362 (-3115 5285);
PAINT MONO (-3115 5285);
FORCEPROP 0 LASTPIN (-3125 5225) $PN CL20
J 0
(-3115 5235);
DISPLAY 0.489362 (-3115 5235);
PAINT MONO (-3115 5235);
FORCEPROP 0 LASTPIN (-3125 5175) $PN CL22
J 0
(-3115 5185);
DISPLAY 0.489362 (-3115 5185);
PAINT MONO (-3115 5185);
FORCEPROP 0 LASTPIN (-3125 5125) $PN CL25
J 0
(-3115 5135);
DISPLAY 0.489362 (-3115 5135);
PAINT MONO (-3115 5135);
FORCEPROP 0 LASTPIN (-3125 5075) $PN CL28
J 0
(-3115 5085);
DISPLAY 0.489362 (-3115 5085);
PAINT MONO (-3115 5085);
FORCEPROP 0 LASTPIN (-3125 5025) $PN CL31
J 0
(-3115 5035);
DISPLAY 0.489362 (-3115 5035);
PAINT MONO (-3115 5035);
FORCEPROP 0 LASTPIN (-3125 4975) $PN CL34
J 0
(-3115 4985);
DISPLAY 0.489362 (-3115 4985);
PAINT MONO (-3115 4985);
FORCEPROP 0 LASTPIN (-3125 4925) $PN CL35
J 0
(-3115 4935);
DISPLAY 0.489362 (-3115 4935);
PAINT MONO (-3115 4935);
FORCEPROP 0 LASTPIN (-3125 4875) $PN CL36
J 0
(-3115 4885);
DISPLAY 0.489362 (-3115 4885);
PAINT MONO (-3115 4885);
FORCEPROP 0 LASTPIN (-3125 4825) $PN CL40
J 0
(-3115 4835);
DISPLAY 0.489362 (-3115 4835);
PAINT MONO (-3115 4835);
FORCEPROP 0 LASTPIN (-3125 4775) $PN CL41
J 0
(-3115 4785);
DISPLAY 0.489362 (-3115 4785);
PAINT MONO (-3115 4785);
FORCEPROP 0 LASTPIN (-3125 4725) $PN CL42
J 0
(-3115 4735);
DISPLAY 0.489362 (-3115 4735);
PAINT MONO (-3115 4735);
FORCEPROP 0 LASTPIN (-3125 4675) $PN CL45
J 0
(-3115 4685);
DISPLAY 0.489362 (-3115 4685);
PAINT MONO (-3115 4685);
FORCEPROP 0 LASTPIN (-3125 4625) $PN CL48
J 0
(-3115 4635);
DISPLAY 0.489362 (-3115 4635);
PAINT MONO (-3115 4635);
FORCEPROP 0 LASTPIN (-3125 4575) $PN CL51
J 0
(-3115 4585);
DISPLAY 0.489362 (-3115 4585);
PAINT MONO (-3115 4585);
FORCEPROP 0 LASTPIN (-3125 4525) $PN CL54
J 0
(-3115 4535);
DISPLAY 0.489362 (-3115 4535);
PAINT MONO (-3115 4535);
FORCEPROP 0 LASTPIN (-3125 4475) $PN CL56
J 0
(-3115 4485);
DISPLAY 0.489362 (-3115 4485);
PAINT MONO (-3115 4485);
FORCEPROP 0 LASTPIN (-3125 4425) $PN CL58
J 0
(-3115 4435);
DISPLAY 0.489362 (-3115 4435);
PAINT MONO (-3115 4435);
FORCEPROP 0 LASTPIN (-3125 4375) $PN CL61
J 0
(-3115 4385);
DISPLAY 0.489362 (-3115 4385);
PAINT MONO (-3115 4385);
FORCEPROP 0 LASTPIN (-3125 4325) $PN CL63
J 0
(-3115 4335);
DISPLAY 0.489362 (-3115 4335);
PAINT MONO (-3115 4335);
FORCEPROP 0 LASTPIN (-3125 4275) $PN CL65
J 0
(-3115 4285);
DISPLAY 0.489362 (-3115 4285);
PAINT MONO (-3115 4285);
FORCEPROP 0 LASTPIN (-3125 4225) $PN CL68
J 0
(-3115 4235);
DISPLAY 0.489362 (-3115 4235);
PAINT MONO (-3115 4235);
FORCEPROP 0 LASTPIN (-3125 4175) $PN CL70
J 0
(-3115 4185);
DISPLAY 0.489362 (-3115 4185);
PAINT MONO (-3115 4185);
FORCEPROP 0 LASTPIN (-3125 4125) $PN CL72
J 0
(-3115 4135);
DISPLAY 0.489362 (-3115 4135);
PAINT MONO (-3115 4135);
FORCEPROP 0 LASTPIN (-3125 4075) $PN CL75
J 0
(-3115 4085);
DISPLAY 0.489362 (-3115 4085);
PAINT MONO (-3115 4085);
FORCEPROP 0 LASTPIN (-3125 4025) $PN CM3
J 0
(-3115 4035);
DISPLAY 0.489362 (-3115 4035);
PAINT MONO (-3115 4035);
FORCEPROP 0 LASTPIN (-3125 3975) $PN CM5
J 0
(-3115 3985);
DISPLAY 0.489362 (-3115 3985);
PAINT MONO (-3115 3985);
FORCEPROP 0 LASTPIN (-3125 3925) $PN CM8
J 0
(-3115 3935);
DISPLAY 0.489362 (-3115 3935);
PAINT MONO (-3115 3935);
FORCEPROP 0 LASTPIN (-3125 3875) $PN CM10
J 0
(-3115 3885);
DISPLAY 0.489362 (-3115 3885);
PAINT MONO (-3115 3885);
FORCEPROP 0 LASTPIN (-3125 3825) $PN CM12
J 0
(-3115 3835);
DISPLAY 0.489362 (-3115 3835);
PAINT MONO (-3115 3835);
FORCEPROP 0 LASTPIN (-3125 3775) $PN CM15
J 0
(-3115 3785);
DISPLAY 0.489362 (-3115 3785);
PAINT MONO (-3115 3785);
FORCEPROP 0 LASTPIN (-3125 3725) $PN CM17
J 0
(-3115 3735);
DISPLAY 0.489362 (-3115 3735);
PAINT MONO (-3115 3735);
FORCEPROP 0 LASTPIN (-3125 3675) $PN CM19
J 0
(-3115 3685);
DISPLAY 0.489362 (-3115 3685);
PAINT MONO (-3115 3685);
FORCEPROP 0 LASTPIN (-3125 3625) $PN CM23
J 0
(-3115 3635);
DISPLAY 0.489362 (-3115 3635);
PAINT MONO (-3115 3635);
FORCEPROP 0 LASTPIN (-3125 3575) $PN CM24
J 0
(-3115 3585);
DISPLAY 0.489362 (-3115 3585);
PAINT MONO (-3115 3585);
FORCEPROP 0 LASTPIN (-3125 3525) $PN CM25
J 0
(-3115 3535);
DISPLAY 0.489362 (-3115 3535);
PAINT MONO (-3115 3535);
FORCEPROP 0 LASTPIN (-3125 3475) $PN CM26
J 0
(-3115 3485);
DISPLAY 0.489362 (-3115 3485);
PAINT MONO (-3115 3485);
FORCEPROP 0 LASTPIN (-3125 3425) $PN CM27
J 0
(-3115 3435);
DISPLAY 0.489362 (-3115 3435);
PAINT MONO (-3115 3435);
FORCEPROP 0 LASTPIN (-3125 3375) $PN CM28
J 0
(-3115 3385);
DISPLAY 0.489362 (-3115 3385);
PAINT MONO (-3115 3385);
FORCEPROP 0 LASTPIN (-3125 3325) $PN CM29
J 0
(-3115 3335);
DISPLAY 0.489362 (-3115 3335);
PAINT MONO (-3115 3335);
FORCEPROP 0 LASTPIN (-3125 3275) $PN CM30
J 0
(-3115 3285);
DISPLAY 0.489362 (-3115 3285);
PAINT MONO (-3115 3285);
FORCEPROP 0 LASTPIN (-3125 3225) $PN CM31
J 0
(-3115 3235);
DISPLAY 0.489362 (-3115 3235);
PAINT MONO (-3115 3235);
FORCEPROP 0 LASTPIN (-3125 3175) $PN CM32
J 0
(-3115 3185);
DISPLAY 0.489362 (-3115 3185);
PAINT MONO (-3115 3185);
FORCEPROP 0 LASTPIN (-3125 3125) $PN CM33
J 0
(-3115 3135);
DISPLAY 0.489362 (-3115 3135);
PAINT MONO (-3115 3135);
FORCEPROP 0 LASTPIN (-3125 3075) $PN CM34
J 0
(-3115 3085);
DISPLAY 0.489362 (-3115 3085);
PAINT MONO (-3115 3085);
FORCEPROP 0 LASTPIN (-3125 3025) $PN CM37
J 0
(-3115 3035);
DISPLAY 0.489362 (-3115 3035);
PAINT MONO (-3115 3035);
FORCEPROP 0 LASTPIN (-3125 2975) $PN CM39
J 0
(-3115 2985);
DISPLAY 0.489362 (-3115 2985);
PAINT MONO (-3115 2985);
FORCEPROP 0 LASTPIN (-3125 2925) $PN CM42
J 0
(-3115 2935);
DISPLAY 0.489362 (-3115 2935);
PAINT MONO (-3115 2935);
FORCEPROP 0 LASTPIN (-3125 2875) $PN CM43
J 0
(-3115 2885);
DISPLAY 0.489362 (-3115 2885);
PAINT MONO (-3115 2885);
FORCEPROP 0 LASTPIN (-3125 2825) $PN CM44
J 0
(-3115 2835);
DISPLAY 0.489362 (-3115 2835);
PAINT MONO (-3115 2835);
FORCEPROP 0 LASTPIN (-3125 2775) $PN CM45
J 0
(-3115 2785);
DISPLAY 0.489362 (-3115 2785);
PAINT MONO (-3115 2785);
FORCEPROP 0 LASTPIN (-3125 2725) $PN CM46
J 0
(-3115 2735);
DISPLAY 0.489362 (-3115 2735);
PAINT MONO (-3115 2735);
FORCEPROP 0 LASTPIN (-3125 2675) $PN CM47
J 0
(-3115 2685);
DISPLAY 0.489362 (-3115 2685);
PAINT MONO (-3115 2685);
FORCEPROP 0 LASTPIN (-3125 2625) $PN CM48
J 0
(-3115 2635);
DISPLAY 0.489362 (-3115 2635);
PAINT MONO (-3115 2635);
FORCEPROP 0 LASTPIN (-3125 2575) $PN CM49
J 0
(-3115 2585);
DISPLAY 0.489362 (-3115 2585);
PAINT MONO (-3115 2585);
FORCEPROP 0 LASTPIN (-3125 2525) $PN CM51
J 0
(-3115 2535);
DISPLAY 0.489362 (-3115 2535);
PAINT MONO (-3115 2535);
FORCEPROP 0 LASTPIN (-3125 2475) $PN CM52
J 0
(-3115 2485);
DISPLAY 0.489362 (-3115 2485);
PAINT MONO (-3115 2485);
FORCEPROP 0 LASTPIN (-3125 2425) $PN CM53
J 0
(-3115 2435);
DISPLAY 0.489362 (-3115 2435);
PAINT MONO (-3115 2435);
FORCEPROP 0 LASTPIN (-3125 2375) $PN CM57
J 0
(-3115 2385);
DISPLAY 0.489362 (-3115 2385);
PAINT MONO (-3115 2385);
FORCEPROP 0 LASTPIN (-3125 2325) $PN CM59
J 0
(-3115 2335);
DISPLAY 0.489362 (-3115 2335);
PAINT MONO (-3115 2335);
FORCEPROP 0 LASTPIN (-3125 2275) $PN CM61
J 0
(-3115 2285);
DISPLAY 0.489362 (-3115 2285);
PAINT MONO (-3115 2285);
FORCEPROP 0 LASTPIN (-3125 2225) $PN CM64
J 0
(-3115 2235);
DISPLAY 0.489362 (-3115 2235);
PAINT MONO (-3115 2235);
FORCEPROP 0 LASTPIN (-3125 2175) $PN CM66
J 0
(-3115 2185);
DISPLAY 0.489362 (-3115 2185);
PAINT MONO (-3115 2185);
FORCEPROP 0 LASTPIN (-3125 2125) $PN CM68
J 0
(-3115 2135);
DISPLAY 0.489362 (-3115 2135);
PAINT MONO (-3115 2135);
FORCEPROP 0 LASTPIN (-3125 2075) $PN CM71
J 0
(-3115 2085);
DISPLAY 0.489362 (-3115 2085);
PAINT MONO (-3115 2085);
FORCEPROP 0 LASTPIN (-3125 2025) $PN CM73
J 0
(-3115 2035);
DISPLAY 0.489362 (-3115 2035);
PAINT MONO (-3115 2035);
FORCEPROP 0 LASTPIN (-3125 1975) $PN CN1
J 0
(-3115 1985);
DISPLAY 0.489362 (-3115 1985);
PAINT MONO (-3115 1985);
FORCEPROP 0 LASTPIN (-3125 1925) $PN CN6
J 0
(-3115 1935);
DISPLAY 0.489362 (-3115 1935);
PAINT MONO (-3115 1935);
FORCEPROP 0 LASTPIN (-3125 1875) $PN CN8
J 0
(-3115 1885);
DISPLAY 0.489362 (-3115 1885);
PAINT MONO (-3115 1885);
FORCEPROP 0 LASTPIN (-3125 1825) $PN CN13
J 0
(-3115 1835);
DISPLAY 0.489362 (-3115 1835);
PAINT MONO (-3115 1835);
FORCEPROP 0 LASTPIN (-3125 1775) $PN CN15
J 0
(-3115 1785);
DISPLAY 0.489362 (-3115 1785);
PAINT MONO (-3115 1785);
FORCEPROP 0 LASTPIN (-3125 1725) $PN CN20
J 0
(-3115 1735);
DISPLAY 0.489362 (-3115 1735);
PAINT MONO (-3115 1735);
FORCEPROP 0 LASTPIN (-3125 1675) $PN CN22
J 0
(-3115 1685);
DISPLAY 0.489362 (-3115 1685);
PAINT MONO (-3115 1685);
FORCEPROP 0 LASTPIN (-3125 1625) $PN CN25
J 0
(-3115 1635);
DISPLAY 0.489362 (-3115 1635);
PAINT MONO (-3115 1635);
FORCEPROP 0 LASTPIN (-3125 1575) $PN CN28
J 0
(-3115 1585);
DISPLAY 0.489362 (-3115 1585);
PAINT MONO (-3115 1585);
FORCEPROP 0 LASTPIN (-3125 1525) $PN CN31
J 0
(-3115 1535);
DISPLAY 0.489362 (-3115 1535);
PAINT MONO (-3115 1535);
FORCEPROP 0 LASTPIN (-3125 1475) $PN CN34
J 0
(-3115 1485);
DISPLAY 0.489362 (-3115 1485);
PAINT MONO (-3115 1485);
FORCEPROP 0 LASTPIN (-3125 1425) $PN CN42
J 0
(-3115 1435);
DISPLAY 0.489362 (-3115 1435);
PAINT MONO (-3115 1435);
FORCEPROP 0 LASTPIN (-3125 1375) $PN CN45
J 0
(-3115 1385);
DISPLAY 0.489362 (-3115 1385);
PAINT MONO (-3115 1385);
FORCEPROP 0 LASTPIN (-3125 1325) $PN CN48
J 0
(-3115 1335);
DISPLAY 0.489362 (-3115 1335);
PAINT MONO (-3115 1335);
FORCEPROP 0 LASTPIN (-3125 1275) $PN CN51
J 0
(-3115 1285);
DISPLAY 0.489362 (-3115 1285);
PAINT MONO (-3115 1285);
FORCEPROP 0 LASTPIN (-3125 1225) $PN CN56
J 0
(-3115 1235);
DISPLAY 0.489362 (-3115 1235);
PAINT MONO (-3115 1235);
FORCEPROP 0 LASTPIN (-3125 1175) $PN CN61
J 0
(-3115 1185);
DISPLAY 0.489362 (-3115 1185);
PAINT MONO (-3115 1185);
FORCEPROP 0 LASTPIN (-3125 1125) $PN CN63
J 0
(-3115 1135);
DISPLAY 0.489362 (-3115 1135);
PAINT MONO (-3115 1135);
FORCEPROP 0 LASTPIN (-3125 1075) $PN CN68
J 0
(-3115 1085);
DISPLAY 0.489362 (-3115 1085);
PAINT MONO (-3115 1085);
FORCEPROP 0 LASTPIN (-3125 1025) $PN CN70
J 0
(-3115 1035);
DISPLAY 0.489362 (-3115 1035);
PAINT MONO (-3115 1035);
FORCEPROP 0 LASTPIN (-3125 975) $PN CN75
J 0
(-3115 985);
DISPLAY 0.489362 (-3115 985);
PAINT MONO (-3115 985);
FORCEPROP 0 LASTPIN (-3125 925) $PN CP3
J 0
(-3115 935);
DISPLAY 0.489362 (-3115 935);
PAINT MONO (-3115 935);
FORCEPROP 0 LASTPIN (-3125 875) $PN CP5
J 0
(-3115 885);
DISPLAY 0.489362 (-3115 885);
PAINT MONO (-3115 885);
FORCEPROP 0 LASTPIN (-3125 825) $PN CP8
J 0
(-3115 835);
DISPLAY 0.489362 (-3115 835);
PAINT MONO (-3115 835);
FORCEPROP 0 LASTPIN (-3125 775) $PN CP10
J 0
(-3115 785);
DISPLAY 0.489362 (-3115 785);
PAINT MONO (-3115 785);
FORCEPROP 0 LASTPIN (-3125 725) $PN CP12
J 0
(-3115 735);
DISPLAY 0.489362 (-3115 735);
PAINT MONO (-3115 735);
FORCEPROP 0 LASTPIN (-3125 675) $PN CP15
J 0
(-3115 685);
DISPLAY 0.489362 (-3115 685);
PAINT MONO (-3115 685);
FORCEPROP 0 LASTPIN (-3125 625) $PN CP17
J 0
(-3115 635);
DISPLAY 0.489362 (-3115 635);
PAINT MONO (-3115 635);
FORCEPROP 0 LASTPIN (-3125 575) $PN CP19
J 0
(-3115 585);
DISPLAY 0.489362 (-3115 585);
PAINT MONO (-3115 585);
FORCEPROP 2 LAST PART_TYPE SMLF
J 0
(-4075 6675);
DISPLAY 1.021277 (-4075 6675);
FORCEPROP 1 LAST MATERIAL IO
J 0
(-4070 6507);
DISPLAY 0.489362 (-4070 6507);
PAINT SKYBLUE (-4070 6507);
FORCEPROP 2 LAST VALUE SOCKET6096_13568-001
J 0
(-4075 6550);
DISPLAY 0.489362 (-4075 6550);
PAINT SKYBLUE (-4075 6550);
FORCEPROP 1 LAST NEEDS_NO_SIZE TRUE
J 0
(-3675 3425);
DISPLAY 0.723404 (-3675 3425);
PAINT GREEN (-3675 3425);
DISPLAY INVISIBLE (-3675 3425);
FORCEPROP 1 LAST CDS_LMAN_SYM_OUTLINE -400,3050,400,-3050
J 0
(-3675 3425);
DISPLAY 0.468085 (-3675 3425);
PAINT GREEN (-3675 3425);
DISPLAY INVISIBLE (-3675 3425);
FORCEPROP 2 LAST CDS_LIB pure_quanta
J 0
(-3675 3425);
DISPLAY INVISIBLE (-3675 3425);
FORCEPROP 1 LAST PATH I15
J 0
(-3675 3425);
DISPLAY 0.723404 (-3675 3425);
PAINT GREEN (-3675 3425);
DISPLAY INVISIBLE (-3675 3425);
FORCEPROP 1 LAST PART_NUMBER DGA^6000030
J 0
(-4070 6634);
DISPLAY 0.489362 (-4070 6634);
PAINT SKYBLUE (-4070 6634);
DISPLAY INVISIBLE (-4070 6634);
FORCEADD GENOA_SP5..39
(-1600 3450);
FORCEPROP 1 LAST LOCATION U25
J 0
(-1995 6600);
DISPLAY 0.489362 (-1995 6600);
PAINT SKYBLUE (-1995 6600);
FORCEPROP 0 LAST $SEC 39
J 0
(-1975 6850);
DISPLAY 0.680851 (-1975 6850);
PAINT MONO (-1975 6850);
DISPLAY INVISIBLE (-1975 6850);
FORCEPROP 0 LAST CDS_SEC 39
J 0
(-2225 6700);
DISPLAY 1.021277 (-2225 6700);
DISPLAY INVISIBLE (-2225 6700);
FORCEPROP 0 LASTPIN (-1050 500) $PN CP22
J 0
(-1040 510);
DISPLAY 0.489362 (-1040 510);
PAINT MONO (-1040 510);
FORCEPROP 0 LASTPIN (-1050 550) $PN CP25
J 0
(-1040 560);
DISPLAY 0.489362 (-1040 560);
PAINT MONO (-1040 560);
FORCEPROP 0 LASTPIN (-1050 600) $PN CP28
J 0
(-1040 610);
DISPLAY 0.489362 (-1040 610);
PAINT MONO (-1040 610);
FORCEPROP 0 LASTPIN (-1050 650) $PN CP31
J 0
(-1040 660);
DISPLAY 0.489362 (-1040 660);
PAINT MONO (-1040 660);
FORCEPROP 0 LASTPIN (-1050 700) $PN CP34
J 0
(-1040 710);
DISPLAY 0.489362 (-1040 710);
PAINT MONO (-1040 710);
FORCEPROP 0 LASTPIN (-1050 750) $PN CP37
J 0
(-1040 760);
DISPLAY 0.489362 (-1040 760);
PAINT MONO (-1040 760);
FORCEPROP 0 LASTPIN (-1050 800) $PN CP39
J 0
(-1040 810);
DISPLAY 0.489362 (-1040 810);
PAINT MONO (-1040 810);
FORCEPROP 0 LASTPIN (-1050 850) $PN CP42
J 0
(-1040 860);
DISPLAY 0.489362 (-1040 860);
PAINT MONO (-1040 860);
FORCEPROP 0 LASTPIN (-1050 900) $PN CP45
J 0
(-1040 910);
DISPLAY 0.489362 (-1040 910);
PAINT MONO (-1040 910);
FORCEPROP 0 LASTPIN (-1050 950) $PN CP48
J 0
(-1040 960);
DISPLAY 0.489362 (-1040 960);
PAINT MONO (-1040 960);
FORCEPROP 0 LASTPIN (-1050 1000) $PN CP51
J 0
(-1040 1010);
DISPLAY 0.489362 (-1040 1010);
PAINT MONO (-1040 1010);
FORCEPROP 0 LASTPIN (-1050 1050) $PN CP54
J 0
(-1040 1060);
DISPLAY 0.489362 (-1040 1060);
PAINT MONO (-1040 1060);
FORCEPROP 0 LASTPIN (-1050 1100) $PN CP57
J 0
(-1040 1110);
DISPLAY 0.489362 (-1040 1110);
PAINT MONO (-1040 1110);
FORCEPROP 0 LASTPIN (-1050 1150) $PN CP59
J 0
(-1040 1160);
DISPLAY 0.489362 (-1040 1160);
PAINT MONO (-1040 1160);
FORCEPROP 0 LASTPIN (-1050 1200) $PN CP61
J 0
(-1040 1210);
DISPLAY 0.489362 (-1040 1210);
PAINT MONO (-1040 1210);
FORCEPROP 0 LASTPIN (-1050 1250) $PN CP64
J 0
(-1040 1260);
DISPLAY 0.489362 (-1040 1260);
PAINT MONO (-1040 1260);
FORCEPROP 0 LASTPIN (-1050 1300) $PN CP66
J 0
(-1040 1310);
DISPLAY 0.489362 (-1040 1310);
PAINT MONO (-1040 1310);
FORCEPROP 0 LASTPIN (-1050 1350) $PN CP68
J 0
(-1040 1360);
DISPLAY 0.489362 (-1040 1360);
PAINT MONO (-1040 1360);
FORCEPROP 0 LASTPIN (-1050 1400) $PN CP71
J 0
(-1040 1410);
DISPLAY 0.489362 (-1040 1410);
PAINT MONO (-1040 1410);
FORCEPROP 0 LASTPIN (-1050 1450) $PN CP73
J 0
(-1040 1460);
DISPLAY 0.489362 (-1040 1460);
PAINT MONO (-1040 1460);
FORCEPROP 0 LASTPIN (-1050 1500) $PN CR1
J 0
(-1040 1510);
DISPLAY 0.489362 (-1040 1510);
PAINT MONO (-1040 1510);
FORCEPROP 0 LASTPIN (-1050 1550) $PN CR4
J 0
(-1040 1560);
DISPLAY 0.489362 (-1040 1560);
PAINT MONO (-1040 1560);
FORCEPROP 0 LASTPIN (-1050 1600) $PN CR6
J 0
(-1040 1610);
DISPLAY 0.489362 (-1040 1610);
PAINT MONO (-1040 1610);
FORCEPROP 0 LASTPIN (-1050 1650) $PN CR8
J 0
(-1040 1660);
DISPLAY 0.489362 (-1040 1660);
PAINT MONO (-1040 1660);
FORCEPROP 0 LASTPIN (-1050 1700) $PN CR11
J 0
(-1040 1710);
DISPLAY 0.489362 (-1040 1710);
PAINT MONO (-1040 1710);
FORCEPROP 0 LASTPIN (-1050 1750) $PN CR13
J 0
(-1040 1760);
DISPLAY 0.489362 (-1040 1760);
PAINT MONO (-1040 1760);
FORCEPROP 0 LASTPIN (-1050 1800) $PN CR15
J 0
(-1040 1810);
DISPLAY 0.489362 (-1040 1810);
PAINT MONO (-1040 1810);
FORCEPROP 0 LASTPIN (-1050 1850) $PN CR18
J 0
(-1040 1860);
DISPLAY 0.489362 (-1040 1860);
PAINT MONO (-1040 1860);
FORCEPROP 0 LASTPIN (-1050 1900) $PN CR20
J 0
(-1040 1910);
DISPLAY 0.489362 (-1040 1910);
PAINT MONO (-1040 1910);
FORCEPROP 0 LASTPIN (-1050 1950) $PN CR22
J 0
(-1040 1960);
DISPLAY 0.489362 (-1040 1960);
PAINT MONO (-1040 1960);
FORCEPROP 0 LASTPIN (-1050 2000) $PN CR25
J 0
(-1040 2010);
DISPLAY 0.489362 (-1040 2010);
PAINT MONO (-1040 2010);
FORCEPROP 0 LASTPIN (-1050 2050) $PN CR28
J 0
(-1040 2060);
DISPLAY 0.489362 (-1040 2060);
PAINT MONO (-1040 2060);
FORCEPROP 0 LASTPIN (-1050 2100) $PN CR31
J 0
(-1040 2110);
DISPLAY 0.489362 (-1040 2110);
PAINT MONO (-1040 2110);
FORCEPROP 0 LASTPIN (-1050 2150) $PN CR34
J 0
(-1040 2160);
DISPLAY 0.489362 (-1040 2160);
PAINT MONO (-1040 2160);
FORCEPROP 0 LASTPIN (-1050 2200) $PN CR35
J 0
(-1040 2210);
DISPLAY 0.489362 (-1040 2210);
PAINT MONO (-1040 2210);
FORCEPROP 0 LASTPIN (-1050 2250) $PN CR36
J 0
(-1040 2260);
DISPLAY 0.489362 (-1040 2260);
PAINT MONO (-1040 2260);
FORCEPROP 0 LASTPIN (-1050 2300) $PN CR40
J 0
(-1040 2310);
DISPLAY 0.489362 (-1040 2310);
PAINT MONO (-1040 2310);
FORCEPROP 0 LASTPIN (-1050 2350) $PN CR41
J 0
(-1040 2360);
DISPLAY 0.489362 (-1040 2360);
PAINT MONO (-1040 2360);
FORCEPROP 0 LASTPIN (-1050 2400) $PN CR42
J 0
(-1040 2410);
DISPLAY 0.489362 (-1040 2410);
PAINT MONO (-1040 2410);
FORCEPROP 0 LASTPIN (-1050 2450) $PN CR45
J 0
(-1040 2460);
DISPLAY 0.489362 (-1040 2460);
PAINT MONO (-1040 2460);
FORCEPROP 0 LASTPIN (-1050 2500) $PN CR48
J 0
(-1040 2510);
DISPLAY 0.489362 (-1040 2510);
PAINT MONO (-1040 2510);
FORCEPROP 0 LASTPIN (-1050 2550) $PN CR51
J 0
(-1040 2560);
DISPLAY 0.489362 (-1040 2560);
PAINT MONO (-1040 2560);
FORCEPROP 0 LASTPIN (-1050 2600) $PN CR54
J 0
(-1040 2610);
DISPLAY 0.489362 (-1040 2610);
PAINT MONO (-1040 2610);
FORCEPROP 0 LASTPIN (-1050 2650) $PN CR56
J 0
(-1040 2660);
DISPLAY 0.489362 (-1040 2660);
PAINT MONO (-1040 2660);
FORCEPROP 0 LASTPIN (-1050 2700) $PN CR58
J 0
(-1040 2710);
DISPLAY 0.489362 (-1040 2710);
PAINT MONO (-1040 2710);
FORCEPROP 0 LASTPIN (-1050 2750) $PN CR61
J 0
(-1040 2760);
DISPLAY 0.489362 (-1040 2760);
PAINT MONO (-1040 2760);
FORCEPROP 0 LASTPIN (-1050 2800) $PN CR63
J 0
(-1040 2810);
DISPLAY 0.489362 (-1040 2810);
PAINT MONO (-1040 2810);
FORCEPROP 0 LASTPIN (-1050 2850) $PN CR65
J 0
(-1040 2860);
DISPLAY 0.489362 (-1040 2860);
PAINT MONO (-1040 2860);
FORCEPROP 0 LASTPIN (-1050 2900) $PN CR68
J 0
(-1040 2910);
DISPLAY 0.489362 (-1040 2910);
PAINT MONO (-1040 2910);
FORCEPROP 0 LASTPIN (-1050 2950) $PN CR70
J 0
(-1040 2960);
DISPLAY 0.489362 (-1040 2960);
PAINT MONO (-1040 2960);
FORCEPROP 0 LASTPIN (-1050 3000) $PN CR72
J 0
(-1040 3010);
DISPLAY 0.489362 (-1040 3010);
PAINT MONO (-1040 3010);
FORCEPROP 0 LASTPIN (-1050 3050) $PN CR75
J 0
(-1040 3060);
DISPLAY 0.489362 (-1040 3060);
PAINT MONO (-1040 3060);
FORCEPROP 0 LASTPIN (-1050 3100) $PN CT3
J 0
(-1040 3110);
DISPLAY 0.489362 (-1040 3110);
PAINT MONO (-1040 3110);
FORCEPROP 0 LASTPIN (-1050 3150) $PN CT8
J 0
(-1040 3160);
DISPLAY 0.489362 (-1040 3160);
PAINT MONO (-1040 3160);
FORCEPROP 0 LASTPIN (-1050 3200) $PN CT10
J 0
(-1040 3210);
DISPLAY 0.489362 (-1040 3210);
PAINT MONO (-1040 3210);
FORCEPROP 0 LASTPIN (-1050 3250) $PN CT15
J 0
(-1040 3260);
DISPLAY 0.489362 (-1040 3260);
PAINT MONO (-1040 3260);
FORCEPROP 0 LASTPIN (-1050 3300) $PN CT17
J 0
(-1040 3310);
DISPLAY 0.489362 (-1040 3310);
PAINT MONO (-1040 3310);
FORCEPROP 0 LASTPIN (-1050 3350) $PN CT23
J 0
(-1040 3360);
DISPLAY 0.489362 (-1040 3360);
PAINT MONO (-1040 3360);
FORCEPROP 0 LASTPIN (-1050 3400) $PN CT24
J 0
(-1040 3410);
DISPLAY 0.489362 (-1040 3410);
PAINT MONO (-1040 3410);
FORCEPROP 0 LASTPIN (-1050 3450) $PN CT25
J 0
(-1040 3460);
DISPLAY 0.489362 (-1040 3460);
PAINT MONO (-1040 3460);
FORCEPROP 0 LASTPIN (-1050 3500) $PN CT26
J 0
(-1040 3510);
DISPLAY 0.489362 (-1040 3510);
PAINT MONO (-1040 3510);
FORCEPROP 0 LASTPIN (-1050 3550) $PN CT27
J 0
(-1040 3560);
DISPLAY 0.489362 (-1040 3560);
PAINT MONO (-1040 3560);
FORCEPROP 0 LASTPIN (-1050 3600) $PN CT28
J 0
(-1040 3610);
DISPLAY 0.489362 (-1040 3610);
PAINT MONO (-1040 3610);
FORCEPROP 0 LASTPIN (-1050 3650) $PN CT29
J 0
(-1040 3660);
DISPLAY 0.489362 (-1040 3660);
PAINT MONO (-1040 3660);
FORCEPROP 0 LASTPIN (-1050 3700) $PN CT30
J 0
(-1040 3710);
DISPLAY 0.489362 (-1040 3710);
PAINT MONO (-1040 3710);
FORCEPROP 0 LASTPIN (-1050 3750) $PN CT31
J 0
(-1040 3760);
DISPLAY 0.489362 (-1040 3760);
PAINT MONO (-1040 3760);
FORCEPROP 0 LASTPIN (-1050 3800) $PN CT32
J 0
(-1040 3810);
DISPLAY 0.489362 (-1040 3810);
PAINT MONO (-1040 3810);
FORCEPROP 0 LASTPIN (-1050 3850) $PN CT33
J 0
(-1040 3860);
DISPLAY 0.489362 (-1040 3860);
PAINT MONO (-1040 3860);
FORCEPROP 0 LASTPIN (-1050 3900) $PN CT34
J 0
(-1040 3910);
DISPLAY 0.489362 (-1040 3910);
PAINT MONO (-1040 3910);
FORCEPROP 0 LASTPIN (-1050 3950) $PN CT37
J 0
(-1040 3960);
DISPLAY 0.489362 (-1040 3960);
PAINT MONO (-1040 3960);
FORCEPROP 0 LASTPIN (-1050 4000) $PN CT39
J 0
(-1040 4010);
DISPLAY 0.489362 (-1040 4010);
PAINT MONO (-1040 4010);
FORCEPROP 0 LASTPIN (-1050 4050) $PN CT42
J 0
(-1040 4060);
DISPLAY 0.489362 (-1040 4060);
PAINT MONO (-1040 4060);
FORCEPROP 0 LASTPIN (-1050 4100) $PN CT43
J 0
(-1040 4110);
DISPLAY 0.489362 (-1040 4110);
PAINT MONO (-1040 4110);
FORCEPROP 0 LASTPIN (-1050 4150) $PN CT44
J 0
(-1040 4160);
DISPLAY 0.489362 (-1040 4160);
PAINT MONO (-1040 4160);
FORCEPROP 0 LASTPIN (-1050 4200) $PN CT45
J 0
(-1040 4210);
DISPLAY 0.489362 (-1040 4210);
PAINT MONO (-1040 4210);
FORCEPROP 0 LASTPIN (-1050 4250) $PN CT46
J 0
(-1040 4260);
DISPLAY 0.489362 (-1040 4260);
PAINT MONO (-1040 4260);
FORCEPROP 0 LASTPIN (-1050 4300) $PN CT47
J 0
(-1040 4310);
DISPLAY 0.489362 (-1040 4310);
PAINT MONO (-1040 4310);
FORCEPROP 0 LASTPIN (-1050 4350) $PN CT48
J 0
(-1040 4360);
DISPLAY 0.489362 (-1040 4360);
PAINT MONO (-1040 4360);
FORCEPROP 0 LASTPIN (-1050 4400) $PN CT49
J 0
(-1040 4410);
DISPLAY 0.489362 (-1040 4410);
PAINT MONO (-1040 4410);
FORCEPROP 0 LASTPIN (-1050 4450) $PN CT50
J 0
(-1040 4460);
DISPLAY 0.489362 (-1040 4460);
PAINT MONO (-1040 4460);
FORCEPROP 0 LASTPIN (-1050 4500) $PN CT51
J 0
(-1040 4510);
DISPLAY 0.489362 (-1040 4510);
PAINT MONO (-1040 4510);
FORCEPROP 0 LASTPIN (-1050 4550) $PN CT53
J 0
(-1040 4560);
DISPLAY 0.489362 (-1040 4560);
PAINT MONO (-1040 4560);
FORCEPROP 0 LASTPIN (-1050 4600) $PN CT59
J 0
(-1040 4610);
DISPLAY 0.489362 (-1040 4610);
PAINT MONO (-1040 4610);
FORCEPROP 0 LASTPIN (-1050 4650) $PN CT61
J 0
(-1040 4660);
DISPLAY 0.489362 (-1040 4660);
PAINT MONO (-1040 4660);
FORCEPROP 0 LASTPIN (-1050 4700) $PN CT66
J 0
(-1040 4710);
DISPLAY 0.489362 (-1040 4710);
PAINT MONO (-1040 4710);
FORCEPROP 0 LASTPIN (-1050 4750) $PN CT68
J 0
(-1040 4760);
DISPLAY 0.489362 (-1040 4760);
PAINT MONO (-1040 4760);
FORCEPROP 0 LASTPIN (-1050 4800) $PN CT73
J 0
(-1040 4810);
DISPLAY 0.489362 (-1040 4810);
PAINT MONO (-1040 4810);
FORCEPROP 0 LASTPIN (-1050 4850) $PN CU1
J 0
(-1040 4860);
DISPLAY 0.489362 (-1040 4860);
PAINT MONO (-1040 4860);
FORCEPROP 0 LASTPIN (-1050 4900) $PN CU4
J 0
(-1040 4910);
DISPLAY 0.489362 (-1040 4910);
PAINT MONO (-1040 4910);
FORCEPROP 0 LASTPIN (-1050 4950) $PN CU6
J 0
(-1040 4960);
DISPLAY 0.489362 (-1040 4960);
PAINT MONO (-1040 4960);
FORCEPROP 0 LASTPIN (-1050 5000) $PN CU8
J 0
(-1040 5010);
DISPLAY 0.489362 (-1040 5010);
PAINT MONO (-1040 5010);
FORCEPROP 0 LASTPIN (-1050 5050) $PN CU11
J 0
(-1040 5060);
DISPLAY 0.489362 (-1040 5060);
PAINT MONO (-1040 5060);
FORCEPROP 0 LASTPIN (-1050 5100) $PN CU13
J 0
(-1040 5110);
DISPLAY 0.489362 (-1040 5110);
PAINT MONO (-1040 5110);
FORCEPROP 0 LASTPIN (-1050 5150) $PN CU15
J 0
(-1040 5160);
DISPLAY 0.489362 (-1040 5160);
PAINT MONO (-1040 5160);
FORCEPROP 0 LASTPIN (-1050 5200) $PN CU18
J 0
(-1040 5210);
DISPLAY 0.489362 (-1040 5210);
PAINT MONO (-1040 5210);
FORCEPROP 0 LASTPIN (-1050 5250) $PN CU20
J 0
(-1040 5260);
DISPLAY 0.489362 (-1040 5260);
PAINT MONO (-1040 5260);
FORCEPROP 0 LASTPIN (-1050 5300) $PN CU22
J 0
(-1040 5310);
DISPLAY 0.489362 (-1040 5310);
PAINT MONO (-1040 5310);
FORCEPROP 0 LASTPIN (-1050 5350) $PN CU25
J 0
(-1040 5360);
DISPLAY 0.489362 (-1040 5360);
PAINT MONO (-1040 5360);
FORCEPROP 0 LASTPIN (-1050 5400) $PN CU28
J 0
(-1040 5410);
DISPLAY 0.489362 (-1040 5410);
PAINT MONO (-1040 5410);
FORCEPROP 0 LASTPIN (-1050 5450) $PN CU31
J 0
(-1040 5460);
DISPLAY 0.489362 (-1040 5460);
PAINT MONO (-1040 5460);
FORCEPROP 0 LASTPIN (-1050 5500) $PN CU34
J 0
(-1040 5510);
DISPLAY 0.489362 (-1040 5510);
PAINT MONO (-1040 5510);
FORCEPROP 0 LASTPIN (-1050 5550) $PN CU42
J 0
(-1040 5560);
DISPLAY 0.489362 (-1040 5560);
PAINT MONO (-1040 5560);
FORCEPROP 0 LASTPIN (-1050 5600) $PN CU45
J 0
(-1040 5610);
DISPLAY 0.489362 (-1040 5610);
PAINT MONO (-1040 5610);
FORCEPROP 0 LASTPIN (-1050 5650) $PN CU48
J 0
(-1040 5660);
DISPLAY 0.489362 (-1040 5660);
PAINT MONO (-1040 5660);
FORCEPROP 0 LASTPIN (-1050 5700) $PN CU51
J 0
(-1040 5710);
DISPLAY 0.489362 (-1040 5710);
PAINT MONO (-1040 5710);
FORCEPROP 0 LASTPIN (-1050 5750) $PN CU54
J 0
(-1040 5760);
DISPLAY 0.489362 (-1040 5760);
PAINT MONO (-1040 5760);
FORCEPROP 0 LASTPIN (-1050 5800) $PN CU56
J 0
(-1040 5810);
DISPLAY 0.489362 (-1040 5810);
PAINT MONO (-1040 5810);
FORCEPROP 0 LASTPIN (-1050 5850) $PN CU61
J 0
(-1040 5860);
DISPLAY 0.489362 (-1040 5860);
PAINT MONO (-1040 5860);
FORCEPROP 0 LASTPIN (-1050 5900) $PN CU63
J 0
(-1040 5910);
DISPLAY 0.489362 (-1040 5910);
PAINT MONO (-1040 5910);
FORCEPROP 0 LASTPIN (-1050 5950) $PN CU65
J 0
(-1040 5960);
DISPLAY 0.489362 (-1040 5960);
PAINT MONO (-1040 5960);
FORCEPROP 0 LASTPIN (-1050 6000) $PN CU68
J 0
(-1040 6010);
DISPLAY 0.489362 (-1040 6010);
PAINT MONO (-1040 6010);
FORCEPROP 0 LASTPIN (-1050 6050) $PN CU70
J 0
(-1040 6060);
DISPLAY 0.489362 (-1040 6060);
PAINT MONO (-1040 6060);
FORCEPROP 0 LASTPIN (-1050 6100) $PN CU72
J 0
(-1040 6110);
DISPLAY 0.489362 (-1040 6110);
PAINT MONO (-1040 6110);
FORCEPROP 0 LASTPIN (-1050 6150) $PN CU75
J 0
(-1040 6160);
DISPLAY 0.489362 (-1040 6160);
PAINT MONO (-1040 6160);
FORCEPROP 0 LASTPIN (-1050 6200) $PN CV3
J 0
(-1040 6210);
DISPLAY 0.489362 (-1040 6210);
PAINT MONO (-1040 6210);
FORCEPROP 0 LASTPIN (-1050 6250) $PN CV5
J 0
(-1040 6260);
DISPLAY 0.489362 (-1040 6260);
PAINT MONO (-1040 6260);
FORCEPROP 0 LASTPIN (-1050 6300) $PN CV8
J 0
(-1040 6310);
DISPLAY 0.489362 (-1040 6310);
PAINT MONO (-1040 6310);
FORCEPROP 0 LASTPIN (-2150 500) $PN CV10
J 2
(-2160 510);
DISPLAY 0.489362 (-2160 510);
PAINT MONO (-2160 510);
FORCEPROP 0 LASTPIN (-2150 550) $PN CV12
J 2
(-2160 560);
DISPLAY 0.489362 (-2160 560);
PAINT MONO (-2160 560);
FORCEPROP 0 LASTPIN (-2150 600) $PN CV15
J 2
(-2160 610);
DISPLAY 0.489362 (-2160 610);
PAINT MONO (-2160 610);
FORCEPROP 0 LASTPIN (-2150 650) $PN CV17
J 2
(-2160 660);
DISPLAY 0.489362 (-2160 660);
PAINT MONO (-2160 660);
FORCEPROP 0 LASTPIN (-2150 700) $PN CV19
J 2
(-2160 710);
DISPLAY 0.489362 (-2160 710);
PAINT MONO (-2160 710);
FORCEPROP 0 LASTPIN (-2150 750) $PN CV22
J 2
(-2160 760);
DISPLAY 0.489362 (-2160 760);
PAINT MONO (-2160 760);
FORCEPROP 0 LASTPIN (-2150 800) $PN CV25
J 2
(-2160 810);
DISPLAY 0.489362 (-2160 810);
PAINT MONO (-2160 810);
FORCEPROP 0 LASTPIN (-2150 850) $PN CV28
J 2
(-2160 860);
DISPLAY 0.489362 (-2160 860);
PAINT MONO (-2160 860);
FORCEPROP 0 LASTPIN (-2150 900) $PN CV31
J 2
(-2160 910);
DISPLAY 0.489362 (-2160 910);
PAINT MONO (-2160 910);
FORCEPROP 0 LASTPIN (-2150 950) $PN CV34
J 2
(-2160 960);
DISPLAY 0.489362 (-2160 960);
PAINT MONO (-2160 960);
FORCEPROP 0 LASTPIN (-2150 1000) $PN CV37
J 2
(-2160 1010);
DISPLAY 0.489362 (-2160 1010);
PAINT MONO (-2160 1010);
FORCEPROP 0 LASTPIN (-2150 1050) $PN CV39
J 2
(-2160 1060);
DISPLAY 0.489362 (-2160 1060);
PAINT MONO (-2160 1060);
FORCEPROP 0 LASTPIN (-2150 1100) $PN CV42
J 2
(-2160 1110);
DISPLAY 0.489362 (-2160 1110);
PAINT MONO (-2160 1110);
FORCEPROP 0 LASTPIN (-2150 1150) $PN CV45
J 2
(-2160 1160);
DISPLAY 0.489362 (-2160 1160);
PAINT MONO (-2160 1160);
FORCEPROP 0 LASTPIN (-2150 1200) $PN CV48
J 2
(-2160 1210);
DISPLAY 0.489362 (-2160 1210);
PAINT MONO (-2160 1210);
FORCEPROP 0 LASTPIN (-2150 1250) $PN CV51
J 2
(-2160 1260);
DISPLAY 0.489362 (-2160 1260);
PAINT MONO (-2160 1260);
FORCEPROP 0 LASTPIN (-2150 1300) $PN CV54
J 2
(-2160 1310);
DISPLAY 0.489362 (-2160 1310);
PAINT MONO (-2160 1310);
FORCEPROP 0 LASTPIN (-2150 1350) $PN CV57
J 2
(-2160 1360);
DISPLAY 0.489362 (-2160 1360);
PAINT MONO (-2160 1360);
FORCEPROP 0 LASTPIN (-2150 1400) $PN CV59
J 2
(-2160 1410);
DISPLAY 0.489362 (-2160 1410);
PAINT MONO (-2160 1410);
FORCEPROP 0 LASTPIN (-2150 1450) $PN CV61
J 2
(-2160 1460);
DISPLAY 0.489362 (-2160 1460);
PAINT MONO (-2160 1460);
FORCEPROP 0 LASTPIN (-2150 1500) $PN CV64
J 2
(-2160 1510);
DISPLAY 0.489362 (-2160 1510);
PAINT MONO (-2160 1510);
FORCEPROP 0 LASTPIN (-2150 1550) $PN CV66
J 2
(-2160 1560);
DISPLAY 0.489362 (-2160 1560);
PAINT MONO (-2160 1560);
FORCEPROP 0 LASTPIN (-2150 1600) $PN CV68
J 2
(-2160 1610);
DISPLAY 0.489362 (-2160 1610);
PAINT MONO (-2160 1610);
FORCEPROP 0 LASTPIN (-2150 1650) $PN CV71
J 2
(-2160 1660);
DISPLAY 0.489362 (-2160 1660);
PAINT MONO (-2160 1660);
FORCEPROP 0 LASTPIN (-2150 1700) $PN CV73
J 2
(-2160 1710);
DISPLAY 0.489362 (-2160 1710);
PAINT MONO (-2160 1710);
FORCEPROP 0 LASTPIN (-2150 1750) $PN CW1
J 2
(-2160 1760);
DISPLAY 0.489362 (-2160 1760);
PAINT MONO (-2160 1760);
FORCEPROP 0 LASTPIN (-2150 1800) $PN CW6
J 2
(-2160 1810);
DISPLAY 0.489362 (-2160 1810);
PAINT MONO (-2160 1810);
FORCEPROP 0 LASTPIN (-2150 1850) $PN CW8
J 2
(-2160 1860);
DISPLAY 0.489362 (-2160 1860);
PAINT MONO (-2160 1860);
FORCEPROP 0 LASTPIN (-2150 1900) $PN CW13
J 2
(-2160 1910);
DISPLAY 0.489362 (-2160 1910);
PAINT MONO (-2160 1910);
FORCEPROP 0 LASTPIN (-2150 1950) $PN CW15
J 2
(-2160 1960);
DISPLAY 0.489362 (-2160 1960);
PAINT MONO (-2160 1960);
FORCEPROP 0 LASTPIN (-2150 2000) $PN CW20
J 2
(-2160 2010);
DISPLAY 0.489362 (-2160 2010);
PAINT MONO (-2160 2010);
FORCEPROP 0 LASTPIN (-2150 2050) $PN CW22
J 2
(-2160 2060);
DISPLAY 0.489362 (-2160 2060);
PAINT MONO (-2160 2060);
FORCEPROP 0 LASTPIN (-2150 2100) $PN CW25
J 2
(-2160 2110);
DISPLAY 0.489362 (-2160 2110);
PAINT MONO (-2160 2110);
FORCEPROP 0 LASTPIN (-2150 2150) $PN CW28
J 2
(-2160 2160);
DISPLAY 0.489362 (-2160 2160);
PAINT MONO (-2160 2160);
FORCEPROP 0 LASTPIN (-2150 2200) $PN CW31
J 2
(-2160 2210);
DISPLAY 0.489362 (-2160 2210);
PAINT MONO (-2160 2210);
FORCEPROP 0 LASTPIN (-2150 2250) $PN CW34
J 2
(-2160 2260);
DISPLAY 0.489362 (-2160 2260);
PAINT MONO (-2160 2260);
FORCEPROP 0 LASTPIN (-2150 2300) $PN CW35
J 2
(-2160 2310);
DISPLAY 0.489362 (-2160 2310);
PAINT MONO (-2160 2310);
FORCEPROP 0 LASTPIN (-2150 2350) $PN CW36
J 2
(-2160 2360);
DISPLAY 0.489362 (-2160 2360);
PAINT MONO (-2160 2360);
FORCEPROP 0 LASTPIN (-2150 2400) $PN CW40
J 2
(-2160 2410);
DISPLAY 0.489362 (-2160 2410);
PAINT MONO (-2160 2410);
FORCEPROP 0 LASTPIN (-2150 2450) $PN CW41
J 2
(-2160 2460);
DISPLAY 0.489362 (-2160 2460);
PAINT MONO (-2160 2460);
FORCEPROP 0 LASTPIN (-2150 2500) $PN CW42
J 2
(-2160 2510);
DISPLAY 0.489362 (-2160 2510);
PAINT MONO (-2160 2510);
FORCEPROP 0 LASTPIN (-2150 2550) $PN CW45
J 2
(-2160 2560);
DISPLAY 0.489362 (-2160 2560);
PAINT MONO (-2160 2560);
FORCEPROP 0 LASTPIN (-2150 2600) $PN CW48
J 2
(-2160 2610);
DISPLAY 0.489362 (-2160 2610);
PAINT MONO (-2160 2610);
FORCEPROP 0 LASTPIN (-2150 2650) $PN CW51
J 2
(-2160 2660);
DISPLAY 0.489362 (-2160 2660);
PAINT MONO (-2160 2660);
FORCEPROP 0 LASTPIN (-2150 2700) $PN CW54
J 2
(-2160 2710);
DISPLAY 0.489362 (-2160 2710);
PAINT MONO (-2160 2710);
FORCEPROP 0 LASTPIN (-2150 2750) $PN CW56
J 2
(-2160 2760);
DISPLAY 0.489362 (-2160 2760);
PAINT MONO (-2160 2760);
FORCEPROP 0 LASTPIN (-2150 2800) $PN CW61
J 2
(-2160 2810);
DISPLAY 0.489362 (-2160 2810);
PAINT MONO (-2160 2810);
FORCEPROP 0 LASTPIN (-2150 2850) $PN CW63
J 2
(-2160 2860);
DISPLAY 0.489362 (-2160 2860);
PAINT MONO (-2160 2860);
FORCEPROP 0 LASTPIN (-2150 2900) $PN CW68
J 2
(-2160 2910);
DISPLAY 0.489362 (-2160 2910);
PAINT MONO (-2160 2910);
FORCEPROP 0 LASTPIN (-2150 2950) $PN CW70
J 2
(-2160 2960);
DISPLAY 0.489362 (-2160 2960);
PAINT MONO (-2160 2960);
FORCEPROP 0 LASTPIN (-2150 3000) $PN CW75
J 2
(-2160 3010);
DISPLAY 0.489362 (-2160 3010);
PAINT MONO (-2160 3010);
FORCEPROP 0 LASTPIN (-2150 3050) $PN CY3
J 2
(-2160 3060);
DISPLAY 0.489362 (-2160 3060);
PAINT MONO (-2160 3060);
FORCEPROP 0 LASTPIN (-2150 3100) $PN CY5
J 2
(-2160 3110);
DISPLAY 0.489362 (-2160 3110);
PAINT MONO (-2160 3110);
FORCEPROP 0 LASTPIN (-2150 3150) $PN CY8
J 2
(-2160 3160);
DISPLAY 0.489362 (-2160 3160);
PAINT MONO (-2160 3160);
FORCEPROP 0 LASTPIN (-2150 3200) $PN CY10
J 2
(-2160 3210);
DISPLAY 0.489362 (-2160 3210);
PAINT MONO (-2160 3210);
FORCEPROP 0 LASTPIN (-2150 3250) $PN CY12
J 2
(-2160 3260);
DISPLAY 0.489362 (-2160 3260);
PAINT MONO (-2160 3260);
FORCEPROP 0 LASTPIN (-2150 3300) $PN CY15
J 2
(-2160 3310);
DISPLAY 0.489362 (-2160 3310);
PAINT MONO (-2160 3310);
FORCEPROP 0 LASTPIN (-2150 3350) $PN CY17
J 2
(-2160 3360);
DISPLAY 0.489362 (-2160 3360);
PAINT MONO (-2160 3360);
FORCEPROP 0 LASTPIN (-2150 3400) $PN CY19
J 2
(-2160 3410);
DISPLAY 0.489362 (-2160 3410);
PAINT MONO (-2160 3410);
FORCEPROP 0 LASTPIN (-2150 3450) $PN CY23
J 2
(-2160 3460);
DISPLAY 0.489362 (-2160 3460);
PAINT MONO (-2160 3460);
FORCEPROP 0 LASTPIN (-2150 3500) $PN CY24
J 2
(-2160 3510);
DISPLAY 0.489362 (-2160 3510);
PAINT MONO (-2160 3510);
FORCEPROP 0 LASTPIN (-2150 3550) $PN CY25
J 2
(-2160 3560);
DISPLAY 0.489362 (-2160 3560);
PAINT MONO (-2160 3560);
FORCEPROP 0 LASTPIN (-2150 3600) $PN CY26
J 2
(-2160 3610);
DISPLAY 0.489362 (-2160 3610);
PAINT MONO (-2160 3610);
FORCEPROP 0 LASTPIN (-2150 3650) $PN CY27
J 2
(-2160 3660);
DISPLAY 0.489362 (-2160 3660);
PAINT MONO (-2160 3660);
FORCEPROP 0 LASTPIN (-2150 3700) $PN CY28
J 2
(-2160 3710);
DISPLAY 0.489362 (-2160 3710);
PAINT MONO (-2160 3710);
FORCEPROP 0 LASTPIN (-2150 3750) $PN CY29
J 2
(-2160 3760);
DISPLAY 0.489362 (-2160 3760);
PAINT MONO (-2160 3760);
FORCEPROP 0 LASTPIN (-2150 3800) $PN CY30
J 2
(-2160 3810);
DISPLAY 0.489362 (-2160 3810);
PAINT MONO (-2160 3810);
FORCEPROP 0 LASTPIN (-2150 3850) $PN CY31
J 2
(-2160 3860);
DISPLAY 0.489362 (-2160 3860);
PAINT MONO (-2160 3860);
FORCEPROP 0 LASTPIN (-2150 3900) $PN CY32
J 2
(-2160 3910);
DISPLAY 0.489362 (-2160 3910);
PAINT MONO (-2160 3910);
FORCEPROP 0 LASTPIN (-2150 3950) $PN CY33
J 2
(-2160 3960);
DISPLAY 0.489362 (-2160 3960);
PAINT MONO (-2160 3960);
FORCEPROP 0 LASTPIN (-2150 4000) $PN CY34
J 2
(-2160 4010);
DISPLAY 0.489362 (-2160 4010);
PAINT MONO (-2160 4010);
FORCEPROP 0 LASTPIN (-2150 4050) $PN CY37
J 2
(-2160 4060);
DISPLAY 0.489362 (-2160 4060);
PAINT MONO (-2160 4060);
FORCEPROP 0 LASTPIN (-2150 4100) $PN CY39
J 2
(-2160 4110);
DISPLAY 0.489362 (-2160 4110);
PAINT MONO (-2160 4110);
FORCEPROP 0 LASTPIN (-2150 4150) $PN CY42
J 2
(-2160 4160);
DISPLAY 0.489362 (-2160 4160);
PAINT MONO (-2160 4160);
FORCEPROP 0 LASTPIN (-2150 4200) $PN CY43
J 2
(-2160 4210);
DISPLAY 0.489362 (-2160 4210);
PAINT MONO (-2160 4210);
FORCEPROP 0 LASTPIN (-2150 4250) $PN CY44
J 2
(-2160 4260);
DISPLAY 0.489362 (-2160 4260);
PAINT MONO (-2160 4260);
FORCEPROP 0 LASTPIN (-2150 4300) $PN CY45
J 2
(-2160 4310);
DISPLAY 0.489362 (-2160 4310);
PAINT MONO (-2160 4310);
FORCEPROP 0 LASTPIN (-2150 4350) $PN CY46
J 2
(-2160 4360);
DISPLAY 0.489362 (-2160 4360);
PAINT MONO (-2160 4360);
FORCEPROP 0 LASTPIN (-2150 4400) $PN CY47
J 2
(-2160 4410);
DISPLAY 0.489362 (-2160 4410);
PAINT MONO (-2160 4410);
FORCEPROP 0 LASTPIN (-2150 4450) $PN CY48
J 2
(-2160 4460);
DISPLAY 0.489362 (-2160 4460);
PAINT MONO (-2160 4460);
FORCEPROP 0 LASTPIN (-2150 4500) $PN CY49
J 2
(-2160 4510);
DISPLAY 0.489362 (-2160 4510);
PAINT MONO (-2160 4510);
FORCEPROP 0 LASTPIN (-2150 4550) $PN CY50
J 2
(-2160 4560);
DISPLAY 0.489362 (-2160 4560);
PAINT MONO (-2160 4560);
FORCEPROP 0 LASTPIN (-2150 4600) $PN CY51
J 2
(-2160 4610);
DISPLAY 0.489362 (-2160 4610);
PAINT MONO (-2160 4610);
FORCEPROP 0 LASTPIN (-2150 4650) $PN CY52
J 2
(-2160 4660);
DISPLAY 0.489362 (-2160 4660);
PAINT MONO (-2160 4660);
FORCEPROP 0 LASTPIN (-2150 4700) $PN CY53
J 2
(-2160 4710);
DISPLAY 0.489362 (-2160 4710);
PAINT MONO (-2160 4710);
FORCEPROP 0 LASTPIN (-2150 4750) $PN CY59
J 2
(-2160 4760);
DISPLAY 0.489362 (-2160 4760);
PAINT MONO (-2160 4760);
FORCEPROP 0 LASTPIN (-2150 4800) $PN CY61
J 2
(-2160 4810);
DISPLAY 0.489362 (-2160 4810);
PAINT MONO (-2160 4810);
FORCEPROP 0 LASTPIN (-2150 4850) $PN CY64
J 2
(-2160 4860);
DISPLAY 0.489362 (-2160 4860);
PAINT MONO (-2160 4860);
FORCEPROP 0 LASTPIN (-2150 4900) $PN CY66
J 2
(-2160 4910);
DISPLAY 0.489362 (-2160 4910);
PAINT MONO (-2160 4910);
FORCEPROP 0 LASTPIN (-2150 4950) $PN CY68
J 2
(-2160 4960);
DISPLAY 0.489362 (-2160 4960);
PAINT MONO (-2160 4960);
FORCEPROP 0 LASTPIN (-2150 5000) $PN CY71
J 2
(-2160 5010);
DISPLAY 0.489362 (-2160 5010);
PAINT MONO (-2160 5010);
FORCEPROP 0 LASTPIN (-2150 5050) $PN CY73
J 2
(-2160 5060);
DISPLAY 0.489362 (-2160 5060);
PAINT MONO (-2160 5060);
FORCEPROP 0 LASTPIN (-2150 5100) $PN DA1
J 2
(-2160 5110);
DISPLAY 0.489362 (-2160 5110);
PAINT MONO (-2160 5110);
FORCEPROP 0 LASTPIN (-2150 5150) $PN DA4
J 2
(-2160 5160);
DISPLAY 0.489362 (-2160 5160);
PAINT MONO (-2160 5160);
FORCEPROP 0 LASTPIN (-2150 5200) $PN DA6
J 2
(-2160 5210);
DISPLAY 0.489362 (-2160 5210);
PAINT MONO (-2160 5210);
FORCEPROP 0 LASTPIN (-2150 5250) $PN DA8
J 2
(-2160 5260);
DISPLAY 0.489362 (-2160 5260);
PAINT MONO (-2160 5260);
FORCEPROP 0 LASTPIN (-2150 5300) $PN DA11
J 2
(-2160 5310);
DISPLAY 0.489362 (-2160 5310);
PAINT MONO (-2160 5310);
FORCEPROP 0 LASTPIN (-2150 5350) $PN DA13
J 2
(-2160 5360);
DISPLAY 0.489362 (-2160 5360);
PAINT MONO (-2160 5360);
FORCEPROP 0 LASTPIN (-2150 5400) $PN DA15
J 2
(-2160 5410);
DISPLAY 0.489362 (-2160 5410);
PAINT MONO (-2160 5410);
FORCEPROP 0 LASTPIN (-2150 5450) $PN DA18
J 2
(-2160 5460);
DISPLAY 0.489362 (-2160 5460);
PAINT MONO (-2160 5460);
FORCEPROP 0 LASTPIN (-2150 5500) $PN DA20
J 2
(-2160 5510);
DISPLAY 0.489362 (-2160 5510);
PAINT MONO (-2160 5510);
FORCEPROP 0 LASTPIN (-2150 5550) $PN DA22
J 2
(-2160 5560);
DISPLAY 0.489362 (-2160 5560);
PAINT MONO (-2160 5560);
FORCEPROP 0 LASTPIN (-2150 5600) $PN DA25
J 2
(-2160 5610);
DISPLAY 0.489362 (-2160 5610);
PAINT MONO (-2160 5610);
FORCEPROP 0 LASTPIN (-2150 5650) $PN DA28
J 2
(-2160 5660);
DISPLAY 0.489362 (-2160 5660);
PAINT MONO (-2160 5660);
FORCEPROP 0 LASTPIN (-2150 5700) $PN DA31
J 2
(-2160 5710);
DISPLAY 0.489362 (-2160 5710);
PAINT MONO (-2160 5710);
FORCEPROP 0 LASTPIN (-2150 5750) $PN DA34
J 2
(-2160 5760);
DISPLAY 0.489362 (-2160 5760);
PAINT MONO (-2160 5760);
FORCEPROP 0 LASTPIN (-2150 5800) $PN DA42
J 2
(-2160 5810);
DISPLAY 0.489362 (-2160 5810);
PAINT MONO (-2160 5810);
FORCEPROP 0 LASTPIN (-2150 5850) $PN DA45
J 2
(-2160 5860);
DISPLAY 0.489362 (-2160 5860);
PAINT MONO (-2160 5860);
FORCEPROP 0 LASTPIN (-2150 5900) $PN DA48
J 2
(-2160 5910);
DISPLAY 0.489362 (-2160 5910);
PAINT MONO (-2160 5910);
FORCEPROP 0 LASTPIN (-2150 5950) $PN DA51
J 2
(-2160 5960);
DISPLAY 0.489362 (-2160 5960);
PAINT MONO (-2160 5960);
FORCEPROP 0 LASTPIN (-2150 6000) $PN DA54
J 2
(-2160 6010);
DISPLAY 0.489362 (-2160 6010);
PAINT MONO (-2160 6010);
FORCEPROP 0 LASTPIN (-2150 6050) $PN DA58
J 2
(-2160 6060);
DISPLAY 0.489362 (-2160 6060);
PAINT MONO (-2160 6060);
FORCEPROP 0 LASTPIN (-2150 6100) $PN DA61
J 2
(-2160 6110);
DISPLAY 0.489362 (-2160 6110);
PAINT MONO (-2160 6110);
FORCEPROP 0 LASTPIN (-2150 6150) $PN DA63
J 2
(-2160 6160);
DISPLAY 0.489362 (-2160 6160);
PAINT MONO (-2160 6160);
FORCEPROP 0 LASTPIN (-2150 6200) $PN DA65
J 2
(-2160 6210);
DISPLAY 0.489362 (-2160 6210);
PAINT MONO (-2160 6210);
FORCEPROP 0 LASTPIN (-2150 6250) $PN DA68
J 2
(-2160 6260);
DISPLAY 0.489362 (-2160 6260);
PAINT MONO (-2160 6260);
FORCEPROP 0 LASTPIN (-2150 6300) $PN DA70
J 2
(-2160 6310);
DISPLAY 0.489362 (-2160 6310);
PAINT MONO (-2160 6310);
FORCEPROP 2 LAST PART_TYPE SMLF
J 0
(-2000 6700);
DISPLAY 1.021277 (-2000 6700);
FORCEPROP 1 LAST MATERIAL IO
J 0
(-1995 6532);
DISPLAY 0.489362 (-1995 6532);
PAINT SKYBLUE (-1995 6532);
FORCEPROP 2 LAST VALUE SOCKET6096_13568-001
J 0
(-2000 6575);
DISPLAY 0.489362 (-2000 6575);
PAINT SKYBLUE (-2000 6575);
FORCEPROP 1 LAST NEEDS_NO_SIZE TRUE
J 0
(-1600 3450);
DISPLAY 0.723404 (-1600 3450);
PAINT GREEN (-1600 3450);
DISPLAY INVISIBLE (-1600 3450);
FORCEPROP 1 LAST CDS_LMAN_SYM_OUTLINE -400,3050,400,-3050
J 0
(-1600 3450);
DISPLAY 0.468085 (-1600 3450);
PAINT GREEN (-1600 3450);
DISPLAY INVISIBLE (-1600 3450);
FORCEPROP 2 LAST CDS_LIB pure_quanta
J 0
(-1600 3450);
DISPLAY INVISIBLE (-1600 3450);
FORCEPROP 1 LAST PATH I16
J 0
(-1600 3450);
DISPLAY 0.723404 (-1600 3450);
PAINT GREEN (-1600 3450);
DISPLAY INVISIBLE (-1600 3450);
FORCEPROP 1 LAST PART_NUMBER DGA^6000030
J 0
(-1995 6659);
DISPLAY 0.489362 (-1995 6659);
PAINT SKYBLUE (-1995 6659);
DISPLAY INVISIBLE (-1995 6659);
FORCEADD UNIVERSAL_GND..1
(-7050 425);
FORCEPROP 3 LASTPIN (-7050 475) SIG_NAME GND\g
J 0
(-7040 485);
DISPLAY 0.659574 (-7040 485);
PAINT MONO (-7040 485);
DISPLAY INVISIBLE (-7040 485);
FORCEPROP 2 LAST CDS_LIB pure_quanta_power
J 0
(-7050 425);
DISPLAY INVISIBLE (-7050 425);
FORCEPROP 1 LAST HDL_POWER GND
J 1
(-7025 350);
DISPLAY 0.872340 (-7025 350);
PAINT GREEN (-7025 350);
DISPLAY INVISIBLE (-7025 350);
FORCEPROP 1 LAST PATH I17
J 0
(-6975 425);
DISPLAY 0.872340 (-6975 425);
PAINT AQUA (-6975 425);
DISPLAY INVISIBLE (-6975 425);
FORCEADD UNIVERSAL_GND..1
(-8500 400);
FORCEPROP 3 LASTPIN (-8500 450) SIG_NAME GND\g
J 0
(-8490 460);
DISPLAY 0.659574 (-8490 460);
PAINT MONO (-8490 460);
DISPLAY INVISIBLE (-8490 460);
FORCEPROP 2 LAST CDS_LIB pure_quanta_power
J 0
(-8500 400);
DISPLAY INVISIBLE (-8500 400);
FORCEPROP 1 LAST HDL_POWER GND
J 1
(-8475 325);
DISPLAY 0.872340 (-8475 325);
PAINT GREEN (-8475 325);
DISPLAY INVISIBLE (-8475 325);
FORCEPROP 1 LAST PATH I18
J 0
(-8425 400);
DISPLAY 0.872340 (-8425 400);
PAINT AQUA (-8425 400);
DISPLAY INVISIBLE (-8425 400);
FORCEADD UNIVERSAL_GND..1
(-6475 425);
FORCEPROP 3 LASTPIN (-6475 475) SIG_NAME GND\g
J 0
(-6465 485);
DISPLAY 0.659574 (-6465 485);
PAINT MONO (-6465 485);
DISPLAY INVISIBLE (-6465 485);
FORCEPROP 2 LAST CDS_LIB pure_quanta_power
J 0
(-6475 425);
DISPLAY INVISIBLE (-6475 425);
FORCEPROP 1 LAST HDL_POWER GND
J 1
(-6450 350);
DISPLAY 0.872340 (-6450 350);
PAINT GREEN (-6450 350);
DISPLAY INVISIBLE (-6450 350);
FORCEPROP 1 LAST PATH I19
J 0
(-6400 425);
DISPLAY 0.872340 (-6400 425);
PAINT AQUA (-6400 425);
DISPLAY INVISIBLE (-6400 425);
FORCEADD UNIVERSAL_GND..1
(-5025 425);
FORCEPROP 3 LASTPIN (-5025 475) SIG_NAME GND\g
J 0
(-5015 485);
DISPLAY 0.659574 (-5015 485);
PAINT MONO (-5015 485);
DISPLAY INVISIBLE (-5015 485);
FORCEPROP 2 LAST CDS_LIB pure_quanta_power
J 0
(-5025 425);
DISPLAY INVISIBLE (-5025 425);
FORCEPROP 1 LAST HDL_POWER GND
J 1
(-5000 350);
DISPLAY 0.872340 (-5000 350);
PAINT GREEN (-5000 350);
DISPLAY INVISIBLE (-5000 350);
FORCEPROP 1 LAST PATH I20
J 0
(-4950 425);
DISPLAY 0.872340 (-4950 425);
PAINT AQUA (-4950 425);
DISPLAY INVISIBLE (-4950 425);
FORCEADD UNIVERSAL_GND..1
(-4400 425);
FORCEPROP 3 LASTPIN (-4400 475) SIG_NAME GND\g
J 0
(-4390 485);
DISPLAY 0.659574 (-4390 485);
PAINT MONO (-4390 485);
DISPLAY INVISIBLE (-4390 485);
FORCEPROP 2 LAST CDS_LIB pure_quanta_power
J 0
(-4400 425);
DISPLAY INVISIBLE (-4400 425);
FORCEPROP 1 LAST HDL_POWER GND
J 1
(-4375 350);
DISPLAY 0.872340 (-4375 350);
PAINT GREEN (-4375 350);
DISPLAY INVISIBLE (-4375 350);
FORCEPROP 1 LAST PATH I21
J 0
(-4325 425);
DISPLAY 0.872340 (-4325 425);
PAINT AQUA (-4325 425);
DISPLAY INVISIBLE (-4325 425);
FORCEADD UNIVERSAL_GND..1
(-2950 400);
FORCEPROP 3 LASTPIN (-2950 450) SIG_NAME GND\g
J 0
(-2940 460);
DISPLAY 0.659574 (-2940 460);
PAINT MONO (-2940 460);
DISPLAY INVISIBLE (-2940 460);
FORCEPROP 2 LAST CDS_LIB pure_quanta_power
J 0
(-2950 400);
DISPLAY INVISIBLE (-2950 400);
FORCEPROP 1 LAST HDL_POWER GND
J 1
(-2925 325);
DISPLAY 0.872340 (-2925 325);
PAINT GREEN (-2925 325);
DISPLAY INVISIBLE (-2925 325);
FORCEPROP 1 LAST PATH I22
J 0
(-2875 400);
DISPLAY 0.872340 (-2875 400);
PAINT AQUA (-2875 400);
DISPLAY INVISIBLE (-2875 400);
FORCEADD UNIVERSAL_GND..1
(-875 400);
FORCEPROP 3 LASTPIN (-875 450) SIG_NAME GND\g
J 0
(-865 460);
DISPLAY 0.659574 (-865 460);
PAINT MONO (-865 460);
DISPLAY INVISIBLE (-865 460);
FORCEPROP 2 LAST CDS_LIB pure_quanta_power
J 0
(-875 400);
DISPLAY INVISIBLE (-875 400);
FORCEPROP 1 LAST HDL_POWER GND
J 1
(-850 325);
DISPLAY 0.872340 (-850 325);
PAINT GREEN (-850 325);
DISPLAY INVISIBLE (-850 325);
FORCEPROP 1 LAST PATH I23
J 0
(-800 400);
DISPLAY 0.872340 (-800 400);
PAINT AQUA (-800 400);
DISPLAY INVISIBLE (-800 400);
FORCEADD UNIVERSAL_GND..1
(-2325 400);
FORCEPROP 3 LASTPIN (-2325 450) SIG_NAME GND\g
J 0
(-2315 460);
DISPLAY 0.659574 (-2315 460);
PAINT MONO (-2315 460);
DISPLAY INVISIBLE (-2315 460);
FORCEPROP 2 LAST CDS_LIB pure_quanta_power
J 0
(-2325 400);
DISPLAY INVISIBLE (-2325 400);
FORCEPROP 1 LAST HDL_POWER GND
J 1
(-2300 325);
DISPLAY 0.872340 (-2300 325);
PAINT GREEN (-2300 325);
DISPLAY INVISIBLE (-2300 325);
FORCEPROP 1 LAST PATH I24
J 0
(-2250 400);
DISPLAY 0.872340 (-2250 400);
PAINT AQUA (-2250 400);
DISPLAY INVISIBLE (-2250 400);
FORCEADD QUANTA_TITLE_BLOCK_C..1
(-100 100);
FORCEPROP 0 LAST CDS_CON_LAST_MODIFIED Thu Sep 14 16:11:54 2023
J 0
(-1985 115);
DISPLAY INVISIBLE (-1985 115);
FORCEPROP 1 LAST CUSTOM_TXT_CDS <CON_LAST_MODIFIED>
J 0
(-1985 115);
DISPLAY 0.978723 (-1985 115);
FORCEPROP 2 LAST CUSTOM_TXT_CDS <XR_PAGE_TITLE>
J 0
(-7990 5350);
DISPLAY 0.638298 (-7990 5350);
PAINT PINK (-7990 5350);
DISPLAY INVISIBLE (-7990 5350);
FORCEPROP 1 LAST CUSTOM_TXT_CDS <NAME_2>
J 0
(-3275 150);
FORCEPROP 1 LAST CUSTOM_TXT_CDS <NAME_1>
J 0
(-3275 275);
FORCEPROP 1 LAST CUSTOM_TXT_CDS <Q_NUMBER>
J 0
(-1503 203);
DISPLAY 1.212766 (-1503 203);
FORCEPROP 1 LAST CUSTOM_TXT_CDS <Q_PROJ>
J 0
(-2482 202);
DISPLAY 1.212766 (-2482 202);
FORCEPROP 1 LAST CUSTOM_TXT_CDS <Q_REV>
J 0
(-284 203);
DISPLAY 1.212766 (-284 203);
FORCEPROP 1 LAST CUSTOM_TXT_CDS <CON_PAGE_NUM> OF <CON_TOTAL_PAGES>
J 0
(-546 118);
DISPLAY 0.978723 (-546 118);
FORCEPROP 1 LAST Q_TITLE CPU0 VSS 2/3
J 0
(-9400 150);
DISPLAY 2.446809 (-9400 150);
PAINT GREEN (-9400 150);
FORCEPROP 2 LAST CDS_LIB pure_quanta
J 0
(-100 100);
DISPLAY INVISIBLE (-100 100);
FORCEPROP 1 LAST CDS_LMAN_SYM_OUTLINE -9475,6775,100,-125
J 0
(-100 100);
DISPLAY 0.468085 (-100 100);
PAINT GREEN (-100 100);
DISPLAY INVISIBLE (-100 100);
FORCEPROP 2 LAST PAGE_BORDER TRUE
J 0
(-7990 5350);
DISPLAY 0.638298 (-7990 5350);
PAINT PINK (-7990 5350);
DISPLAY INVISIBLE (-7990 5350);
FORCEPROP 2 LAST CDS_XR_PAGE_TITLE CR-32 : @T6G_MB_LIB.T6G(SCH_1):PAGE32
J 0
(-7990 5350);
DISPLAY 0.638298 (-7990 5350);
PAINT PINK (-7990 5350);
DISPLAY INVISIBLE (-7990 5350);
FORCEPROP 1 LAST Q_DEPT BU9
J 1
(-3863 149);
DISPLAY 1.957447 (-3863 149);
PAINT GREEN (-3863 149);
DISPLAY INVISIBLE (-3863 149);
FORCEPROP 1 LAST COMMENT_BODY TRUE
J 0
(-88 87);
DISPLAY 0.978723 (-88 87);
PAINT GREEN (-88 87);
DISPLAY INVISIBLE (-88 87);
WIRE 16 -1 (-8500 6400)(-8325 6400);
WIRE 16 -1 (-8500 6400)(-8500 6350);
WIRE 16 -1 (-8325 6350)(-8500 6350);
WIRE 16 -1 (-8500 6350)(-8500 6300);
WIRE 16 -1 (-8500 6300)(-8325 6300);
WIRE 16 -1 (-8500 6300)(-8500 6250);
WIRE 16 -1 (-8500 6250)(-8325 6250);
WIRE 16 -1 (-8500 6250)(-8500 6200);
WIRE 16 -1 (-8500 6200)(-8325 6200);
WIRE 16 -1 (-8500 6200)(-8500 6150);
WIRE 16 -1 (-8500 6150)(-8325 6150);
WIRE 16 -1 (-8500 6150)(-8500 6100);
WIRE 16 -1 (-8325 6100)(-8500 6100);
WIRE 16 -1 (-8500 6100)(-8500 6050);
WIRE 16 -1 (-8500 6050)(-8325 6050);
WIRE 16 -1 (-8500 6050)(-8500 6000);
WIRE 16 -1 (-8500 6000)(-8325 6000);
WIRE 16 -1 (-8500 6000)(-8500 5950);
WIRE 16 -1 (-8500 5950)(-8325 5950);
WIRE 16 -1 (-8500 5950)(-8500 5900);
WIRE 16 -1 (-8500 5900)(-8325 5900);
WIRE 16 -1 (-8500 5900)(-8500 5850);
WIRE 16 -1 (-8325 5850)(-8500 5850);
WIRE 16 -1 (-8500 5850)(-8500 5800);
WIRE 16 -1 (-8500 5800)(-8325 5800);
WIRE 16 -1 (-8500 5800)(-8500 5750);
WIRE 16 -1 (-8500 5750)(-8325 5750);
WIRE 16 -1 (-8500 5750)(-8500 5700);
WIRE 16 -1 (-8500 5700)(-8325 5700);
WIRE 16 -1 (-8500 5700)(-8500 5650);
WIRE 16 -1 (-8500 5650)(-8325 5650);
WIRE 16 -1 (-8500 5650)(-8500 5600);
WIRE 16 -1 (-8325 5600)(-8500 5600);
WIRE 16 -1 (-8500 5600)(-8500 5550);
WIRE 16 -1 (-8500 5550)(-8325 5550);
WIRE 16 -1 (-8500 5550)(-8500 5500);
WIRE 16 -1 (-8500 5500)(-8325 5500);
WIRE 16 -1 (-8500 5500)(-8500 5450);
WIRE 16 -1 (-8500 5450)(-8325 5450);
WIRE 16 -1 (-8500 5450)(-8500 5400);
WIRE 16 -1 (-8500 5400)(-8325 5400);
WIRE 16 -1 (-8500 5400)(-8500 5350);
WIRE 16 -1 (-8325 5350)(-8500 5350);
WIRE 16 -1 (-8500 5350)(-8500 5300);
WIRE 16 -1 (-8500 5300)(-8325 5300);
WIRE 16 -1 (-8500 5300)(-8500 5250);
WIRE 16 -1 (-8500 5250)(-8325 5250);
WIRE 16 -1 (-8500 5250)(-8500 5200);
WIRE 16 -1 (-8500 5200)(-8325 5200);
WIRE 16 -1 (-8500 5200)(-8500 5150);
WIRE 16 -1 (-8500 5150)(-8325 5150);
WIRE 16 -1 (-8500 5150)(-8500 5100);
WIRE 16 -1 (-8325 5100)(-8500 5100);
WIRE 16 -1 (-8500 5100)(-8500 5050);
WIRE 16 -1 (-8500 5050)(-8325 5050);
WIRE 16 -1 (-8500 5050)(-8500 5000);
WIRE 16 -1 (-8500 5000)(-8325 5000);
WIRE 16 -1 (-8500 5000)(-8500 4950);
WIRE 16 -1 (-8500 4950)(-8325 4950);
WIRE 16 -1 (-8500 4950)(-8500 4900);
WIRE 16 -1 (-8500 4900)(-8325 4900);
WIRE 16 -1 (-8500 4900)(-8500 4850);
WIRE 16 -1 (-8325 4850)(-8500 4850);
WIRE 16 -1 (-8500 4850)(-8500 4800);
WIRE 16 -1 (-8500 4800)(-8325 4800);
WIRE 16 -1 (-8500 4800)(-8500 4750);
WIRE 16 -1 (-8500 4750)(-8325 4750);
WIRE 16 -1 (-8500 4750)(-8500 4700);
WIRE 16 -1 (-8500 4700)(-8325 4700);
WIRE 16 -1 (-8500 4700)(-8500 4650);
WIRE 16 -1 (-8500 4650)(-8325 4650);
WIRE 16 -1 (-8500 4650)(-8500 4600);
WIRE 16 -1 (-8325 4600)(-8500 4600);
WIRE 16 -1 (-8500 4600)(-8500 4550);
WIRE 16 -1 (-8500 4550)(-8325 4550);
WIRE 16 -1 (-8500 4550)(-8500 4500);
WIRE 16 -1 (-8500 4500)(-8325 4500);
WIRE 16 -1 (-8500 4500)(-8500 4450);
WIRE 16 -1 (-8500 4450)(-8325 4450);
WIRE 16 -1 (-8500 4450)(-8500 4400);
WIRE 16 -1 (-8500 4400)(-8325 4400);
WIRE 16 -1 (-8500 4400)(-8500 4350);
WIRE 16 -1 (-8325 4350)(-8500 4350);
WIRE 16 -1 (-8500 4350)(-8500 4300);
WIRE 16 -1 (-8500 4300)(-8325 4300);
WIRE 16 -1 (-8500 4300)(-8500 4250);
WIRE 16 -1 (-8500 4250)(-8325 4250);
WIRE 16 -1 (-8500 4250)(-8500 4200);
WIRE 16 -1 (-8500 4200)(-8325 4200);
WIRE 16 -1 (-8500 4200)(-8500 4150);
WIRE 16 -1 (-8500 4150)(-8325 4150);
WIRE 16 -1 (-8500 4150)(-8500 4100);
WIRE 16 -1 (-8500 4100)(-8325 4100);
WIRE 16 -1 (-8500 4100)(-8500 4050);
WIRE 16 -1 (-8325 4050)(-8500 4050);
WIRE 16 -1 (-8500 4050)(-8500 4000);
WIRE 16 -1 (-8500 4000)(-8325 4000);
WIRE 16 -1 (-8500 4000)(-8500 3950);
WIRE 16 -1 (-8500 3950)(-8325 3950);
WIRE 16 -1 (-8500 3950)(-8500 3900);
WIRE 16 -1 (-8500 3900)(-8325 3900);
WIRE 16 -1 (-8500 3900)(-8500 3850);
WIRE 16 -1 (-8500 3850)(-8325 3850);
WIRE 16 -1 (-8500 3850)(-8500 3800);
WIRE 16 -1 (-8325 3800)(-8500 3800);
WIRE 16 -1 (-8500 3800)(-8500 3750);
WIRE 16 -1 (-8500 3750)(-8325 3750);
WIRE 16 -1 (-8500 3750)(-8500 3700);
WIRE 16 -1 (-8500 3700)(-8325 3700);
WIRE 16 -1 (-8500 3700)(-8500 3650);
WIRE 16 -1 (-8500 3650)(-8325 3650);
WIRE 16 -1 (-8500 3650)(-8500 3600);
WIRE 16 -1 (-8500 3600)(-8325 3600);
WIRE 16 -1 (-8500 3600)(-8500 3550);
WIRE 16 -1 (-8325 3550)(-8500 3550);
WIRE 16 -1 (-8500 3550)(-8500 3500);
WIRE 16 -1 (-8500 3500)(-8325 3500);
WIRE 16 -1 (-8500 3500)(-8500 3450);
WIRE 16 -1 (-8500 3450)(-8325 3450);
WIRE 16 -1 (-8500 3450)(-8500 3400);
WIRE 16 -1 (-8500 3400)(-8325 3400);
WIRE 16 -1 (-8500 3400)(-8500 3350);
WIRE 16 -1 (-8500 3350)(-8325 3350);
WIRE 16 -1 (-8500 3350)(-8500 3300);
WIRE 16 -1 (-8325 3300)(-8500 3300);
WIRE 16 -1 (-8500 3300)(-8500 3250);
WIRE 16 -1 (-8500 3250)(-8325 3250);
WIRE 16 -1 (-8500 3250)(-8500 3200);
WIRE 16 -1 (-8500 3200)(-8325 3200);
WIRE 16 -1 (-8500 3200)(-8500 3150);
WIRE 16 -1 (-8500 3150)(-8325 3150);
WIRE 16 -1 (-8500 3150)(-8500 3100);
WIRE 16 -1 (-8500 3100)(-8325 3100);
WIRE 16 -1 (-8500 3100)(-8500 3050);
WIRE 16 -1 (-8325 3050)(-8500 3050);
WIRE 16 -1 (-8500 3050)(-8500 3000);
WIRE 16 -1 (-8500 3000)(-8325 3000);
WIRE 16 -1 (-8500 3000)(-8500 2950);
WIRE 16 -1 (-8500 2950)(-8325 2950);
WIRE 16 -1 (-8500 2950)(-8500 2900);
WIRE 16 -1 (-8500 2900)(-8325 2900);
WIRE 16 -1 (-8500 2900)(-8500 2850);
WIRE 16 -1 (-8500 2850)(-8325 2850);
WIRE 16 -1 (-8500 2850)(-8500 2800);
WIRE 16 -1 (-8325 2800)(-8500 2800);
WIRE 16 -1 (-8500 2800)(-8500 2750);
WIRE 16 -1 (-8500 2750)(-8325 2750);
WIRE 16 -1 (-8500 2750)(-8500 2700);
WIRE 16 -1 (-8500 2700)(-8325 2700);
WIRE 16 -1 (-8500 2700)(-8500 2650);
WIRE 16 -1 (-8500 2650)(-8325 2650);
WIRE 16 -1 (-8500 2650)(-8500 2600);
WIRE 16 -1 (-8500 2600)(-8325 2600);
WIRE 16 -1 (-8500 2600)(-8500 2550);
WIRE 16 -1 (-8325 2550)(-8500 2550);
WIRE 16 -1 (-8500 2550)(-8500 2500);
WIRE 16 -1 (-8500 2500)(-8325 2500);
WIRE 16 -1 (-8500 2500)(-8500 2450);
WIRE 16 -1 (-8500 2450)(-8325 2450);
WIRE 16 -1 (-8500 2450)(-8500 2400);
WIRE 16 -1 (-8500 2400)(-8325 2400);
WIRE 16 -1 (-8500 2400)(-8500 2350);
WIRE 16 -1 (-8500 2350)(-8325 2350);
WIRE 16 -1 (-8500 2350)(-8500 2300);
WIRE 16 -1 (-8325 2300)(-8500 2300);
WIRE 16 -1 (-8500 2300)(-8500 2250);
WIRE 16 -1 (-8500 2250)(-8325 2250);
WIRE 16 -1 (-8500 2250)(-8500 2200);
WIRE 16 -1 (-8500 2200)(-8325 2200);
WIRE 16 -1 (-8500 2200)(-8500 2150);
WIRE 16 -1 (-8500 2150)(-8325 2150);
WIRE 16 -1 (-8500 2150)(-8500 2100);
WIRE 16 -1 (-8500 2100)(-8325 2100);
WIRE 16 -1 (-8500 2100)(-8500 2050);
WIRE 16 -1 (-8500 2050)(-8325 2050);
WIRE 16 -1 (-8500 2050)(-8500 2000);
WIRE 16 -1 (-8325 2000)(-8500 2000);
WIRE 16 -1 (-8500 2000)(-8500 1950);
WIRE 16 -1 (-8500 1950)(-8325 1950);
WIRE 16 -1 (-8500 1950)(-8500 1900);
WIRE 16 -1 (-8500 1900)(-8325 1900);
WIRE 16 -1 (-8500 1900)(-8500 1850);
WIRE 16 -1 (-8500 1850)(-8325 1850);
WIRE 16 -1 (-8500 1850)(-8500 1800);
WIRE 16 -1 (-8500 1800)(-8325 1800);
WIRE 16 -1 (-8500 1800)(-8500 1750);
WIRE 16 -1 (-8325 1750)(-8500 1750);
WIRE 16 -1 (-8500 1750)(-8500 1700);
WIRE 16 -1 (-8500 1700)(-8325 1700);
WIRE 16 -1 (-8500 1700)(-8500 1650);
WIRE 16 -1 (-8500 1650)(-8325 1650);
WIRE 16 -1 (-8500 1650)(-8500 1600);
WIRE 16 -1 (-8500 1600)(-8325 1600);
WIRE 16 -1 (-8500 1600)(-8500 1550);
WIRE 16 -1 (-8500 1550)(-8325 1550);
WIRE 16 -1 (-8500 1550)(-8500 1500);
WIRE 16 -1 (-8325 1500)(-8500 1500);
WIRE 16 -1 (-8500 1500)(-8500 1450);
WIRE 16 -1 (-8500 1450)(-8325 1450);
WIRE 16 -1 (-8500 1450)(-8500 1400);
WIRE 16 -1 (-8500 1400)(-8325 1400);
WIRE 16 -1 (-8500 1400)(-8500 1350);
WIRE 16 -1 (-8500 1350)(-8325 1350);
WIRE 16 -1 (-8500 1350)(-8500 1300);
WIRE 16 -1 (-8500 1300)(-8325 1300);
WIRE 16 -1 (-8500 1300)(-8500 1250);
WIRE 16 -1 (-8325 1250)(-8500 1250);
WIRE 16 -1 (-8500 1250)(-8500 1200);
WIRE 16 -1 (-8500 1200)(-8325 1200);
WIRE 16 -1 (-8500 1200)(-8500 1150);
WIRE 16 -1 (-8500 1150)(-8325 1150);
WIRE 16 -1 (-8500 1150)(-8500 1100);
WIRE 16 -1 (-8500 1100)(-8325 1100);
WIRE 16 -1 (-8500 1100)(-8500 1050);
WIRE 16 -1 (-8500 1050)(-8325 1050);
WIRE 16 -1 (-8500 1050)(-8500 1000);
WIRE 16 -1 (-8325 1000)(-8500 1000);
WIRE 16 -1 (-8500 1000)(-8500 950);
WIRE 16 -1 (-8500 950)(-8325 950);
WIRE 16 -1 (-8500 950)(-8500 900);
WIRE 16 -1 (-8500 900)(-8325 900);
WIRE 16 -1 (-8500 900)(-8500 850);
WIRE 16 -1 (-8500 850)(-8325 850);
WIRE 16 -1 (-8500 850)(-8500 800);
WIRE 16 -1 (-8500 800)(-8325 800);
WIRE 16 -1 (-8500 800)(-8500 750);
WIRE 16 -1 (-8325 750)(-8500 750);
WIRE 16 -1 (-8500 750)(-8500 700);
WIRE 16 -1 (-8500 700)(-8325 700);
WIRE 16 -1 (-8500 700)(-8500 650);
WIRE 16 -1 (-8500 650)(-8325 650);
WIRE 16 -1 (-8500 650)(-8500 600);
WIRE 16 -1 (-8500 600)(-8325 600);
WIRE 16 -1 (-8500 600)(-8500 550);
WIRE 16 -1 (-8500 550)(-8325 550);
WIRE 16 -1 (-8500 550)(-8500 500);
WIRE 16 -1 (-8325 500)(-8500 500);
WIRE 16 -1 (-8500 500)(-8500 450);
WIRE 16 -1 (-7225 6400)(-7050 6400);
WIRE 16 -1 (-7050 6400)(-7050 6350);
WIRE 16 -1 (-7050 6350)(-7050 6300);
WIRE 16 -1 (-7225 6350)(-7050 6350);
WIRE 16 -1 (-7050 6300)(-7050 6250);
WIRE 16 -1 (-7225 6300)(-7050 6300);
WIRE 16 -1 (-7050 6250)(-7050 6200);
WIRE 16 -1 (-7225 6250)(-7050 6250);
WIRE 16 -1 (-7050 6200)(-7050 6150);
WIRE 16 -1 (-7225 6200)(-7050 6200);
WIRE 16 -1 (-7225 6150)(-7050 6150);
WIRE 16 -1 (-7050 6150)(-7050 6100);
WIRE 16 -1 (-7050 6100)(-7050 6050);
WIRE 16 -1 (-7225 6100)(-7050 6100);
WIRE 16 -1 (-7050 6050)(-7050 6000);
WIRE 16 -1 (-7225 6050)(-7050 6050);
WIRE 16 -1 (-7050 6000)(-7050 5950);
WIRE 16 -1 (-7225 6000)(-7050 6000);
WIRE 16 -1 (-7050 5950)(-7050 5900);
WIRE 16 -1 (-7225 5950)(-7050 5950);
WIRE 16 -1 (-7050 5900)(-7050 5850);
WIRE 16 -1 (-7225 5900)(-7050 5900);
WIRE 16 -1 (-7050 5850)(-7050 5800);
WIRE 16 -1 (-7225 5850)(-7050 5850);
WIRE 16 -1 (-7050 5800)(-7050 5750);
WIRE 16 -1 (-7225 5800)(-7050 5800);
WIRE 16 -1 (-7050 5750)(-7050 5700);
WIRE 16 -1 (-7225 5750)(-7050 5750);
WIRE 16 -1 (-7050 5700)(-7050 5650);
WIRE 16 -1 (-7225 5700)(-7050 5700);
WIRE 16 -1 (-7050 5650)(-7050 5600);
WIRE 16 -1 (-7225 5650)(-7050 5650);
WIRE 16 -1 (-7050 5600)(-7050 5550);
WIRE 16 -1 (-7225 5600)(-7050 5600);
WIRE 16 -1 (-7050 5550)(-7050 5500);
WIRE 16 -1 (-7225 5550)(-7050 5550);
WIRE 16 -1 (-7050 5500)(-7050 5450);
WIRE 16 -1 (-7225 5500)(-7050 5500);
WIRE 16 -1 (-7050 5450)(-7050 5400);
WIRE 16 -1 (-7225 5450)(-7050 5450);
WIRE 16 -1 (-7050 5400)(-7050 5350);
WIRE 16 -1 (-7225 5400)(-7050 5400);
WIRE 16 -1 (-7050 5350)(-7050 5300);
WIRE 16 -1 (-7225 5350)(-7050 5350);
WIRE 16 -1 (-7050 5300)(-7050 5250);
WIRE 16 -1 (-7225 5300)(-7050 5300);
WIRE 16 -1 (-7050 5250)(-7050 5200);
WIRE 16 -1 (-7225 5250)(-7050 5250);
WIRE 16 -1 (-7050 5200)(-7050 5150);
WIRE 16 -1 (-7225 5200)(-7050 5200);
WIRE 16 -1 (-7050 5150)(-7050 5100);
WIRE 16 -1 (-7225 5150)(-7050 5150);
WIRE 16 -1 (-7050 5100)(-7050 5050);
WIRE 16 -1 (-7225 5100)(-7050 5100);
WIRE 16 -1 (-7050 5050)(-7050 5000);
WIRE 16 -1 (-7225 5050)(-7050 5050);
WIRE 16 -1 (-7050 5000)(-7050 4950);
WIRE 16 -1 (-7225 5000)(-7050 5000);
WIRE 16 -1 (-7050 4950)(-7050 4900);
WIRE 16 -1 (-7225 4950)(-7050 4950);
WIRE 16 -1 (-7050 4900)(-7050 4850);
WIRE 16 -1 (-7225 4900)(-7050 4900);
WIRE 16 -1 (-7050 4850)(-7050 4800);
WIRE 16 -1 (-7225 4850)(-7050 4850);
WIRE 16 -1 (-7050 4800)(-7050 4750);
WIRE 16 -1 (-7225 4800)(-7050 4800);
WIRE 16 -1 (-7050 4750)(-7050 4700);
WIRE 16 -1 (-7225 4750)(-7050 4750);
WIRE 16 -1 (-7050 4700)(-7050 4650);
WIRE 16 -1 (-7225 4700)(-7050 4700);
WIRE 16 -1 (-7050 4650)(-7050 4600);
WIRE 16 -1 (-7225 4650)(-7050 4650);
WIRE 16 -1 (-7050 4600)(-7050 4550);
WIRE 16 -1 (-7225 4600)(-7050 4600);
WIRE 16 -1 (-7050 4550)(-7050 4500);
WIRE 16 -1 (-7225 4550)(-7050 4550);
WIRE 16 -1 (-7050 4500)(-7050 4450);
WIRE 16 -1 (-7225 4500)(-7050 4500);
WIRE 16 -1 (-7050 4450)(-7050 4400);
WIRE 16 -1 (-7225 4450)(-7050 4450);
WIRE 16 -1 (-7050 4400)(-7050 4350);
WIRE 16 -1 (-7225 4400)(-7050 4400);
WIRE 16 -1 (-7050 4350)(-7050 4300);
WIRE 16 -1 (-7225 4350)(-7050 4350);
WIRE 16 -1 (-7050 4300)(-7050 4250);
WIRE 16 -1 (-7225 4300)(-7050 4300);
WIRE 16 -1 (-7050 4250)(-7050 4200);
WIRE 16 -1 (-7225 4250)(-7050 4250);
WIRE 16 -1 (-7050 4200)(-7050 4150);
WIRE 16 -1 (-7225 4200)(-7050 4200);
WIRE 16 -1 (-7050 4150)(-7050 4100);
WIRE 16 -1 (-7225 4150)(-7050 4150);
WIRE 16 -1 (-7225 4100)(-7050 4100);
WIRE 16 -1 (-7050 4100)(-7050 4050);
WIRE 16 -1 (-7050 4050)(-7050 4000);
WIRE 16 -1 (-7225 4050)(-7050 4050);
WIRE 16 -1 (-7050 4000)(-7050 3950);
WIRE 16 -1 (-7225 4000)(-7050 4000);
WIRE 16 -1 (-7050 3950)(-7050 3900);
WIRE 16 -1 (-7225 3950)(-7050 3950);
WIRE 16 -1 (-7050 3900)(-7050 3850);
WIRE 16 -1 (-7225 3900)(-7050 3900);
WIRE 16 -1 (-7050 3850)(-7050 3800);
WIRE 16 -1 (-7225 3850)(-7050 3850);
WIRE 16 -1 (-7050 3800)(-7050 3750);
WIRE 16 -1 (-7225 3800)(-7050 3800);
WIRE 16 -1 (-7050 3750)(-7050 3700);
WIRE 16 -1 (-7225 3750)(-7050 3750);
WIRE 16 -1 (-7050 3700)(-7050 3650);
WIRE 16 -1 (-7225 3700)(-7050 3700);
WIRE 16 -1 (-7050 3650)(-7050 3600);
WIRE 16 -1 (-7225 3650)(-7050 3650);
WIRE 16 -1 (-7050 3600)(-7050 3550);
WIRE 16 -1 (-7225 3600)(-7050 3600);
WIRE 16 -1 (-7050 3550)(-7050 3500);
WIRE 16 -1 (-7225 3550)(-7050 3550);
WIRE 16 -1 (-7050 3500)(-7050 3450);
WIRE 16 -1 (-7225 3500)(-7050 3500);
WIRE 16 -1 (-7050 3450)(-7050 3400);
WIRE 16 -1 (-7225 3450)(-7050 3450);
WIRE 16 -1 (-7050 3400)(-7050 3350);
WIRE 16 -1 (-7225 3400)(-7050 3400);
WIRE 16 -1 (-7050 3350)(-7050 3300);
WIRE 16 -1 (-7225 3350)(-7050 3350);
WIRE 16 -1 (-7050 3300)(-7050 3250);
WIRE 16 -1 (-7225 3300)(-7050 3300);
WIRE 16 -1 (-7050 3250)(-7050 3200);
WIRE 16 -1 (-7225 3250)(-7050 3250);
WIRE 16 -1 (-7050 3200)(-7050 3150);
WIRE 16 -1 (-7225 3200)(-7050 3200);
WIRE 16 -1 (-7050 3150)(-7050 3100);
WIRE 16 -1 (-7225 3150)(-7050 3150);
WIRE 16 -1 (-7050 3100)(-7050 3050);
WIRE 16 -1 (-7225 3100)(-7050 3100);
WIRE 16 -1 (-7050 3050)(-7050 3000);
WIRE 16 -1 (-7225 3050)(-7050 3050);
WIRE 16 -1 (-7050 3000)(-7050 2950);
WIRE 16 -1 (-7225 3000)(-7050 3000);
WIRE 16 -1 (-7050 2950)(-7050 2900);
WIRE 16 -1 (-7225 2950)(-7050 2950);
WIRE 16 -1 (-7050 2900)(-7050 2850);
WIRE 16 -1 (-7225 2900)(-7050 2900);
WIRE 16 -1 (-7050 2850)(-7050 2800);
WIRE 16 -1 (-7225 2850)(-7050 2850);
WIRE 16 -1 (-7050 2800)(-7050 2750);
WIRE 16 -1 (-7225 2800)(-7050 2800);
WIRE 16 -1 (-7050 2750)(-7050 2700);
WIRE 16 -1 (-7225 2750)(-7050 2750);
WIRE 16 -1 (-7050 2700)(-7050 2650);
WIRE 16 -1 (-7225 2700)(-7050 2700);
WIRE 16 -1 (-7050 2650)(-7050 2600);
WIRE 16 -1 (-7225 2650)(-7050 2650);
WIRE 16 -1 (-7050 2600)(-7050 2550);
WIRE 16 -1 (-7225 2600)(-7050 2600);
WIRE 16 -1 (-7050 2550)(-7050 2500);
WIRE 16 -1 (-7225 2550)(-7050 2550);
WIRE 16 -1 (-7050 2500)(-7050 2450);
WIRE 16 -1 (-7225 2500)(-7050 2500);
WIRE 16 -1 (-7050 2450)(-7050 2400);
WIRE 16 -1 (-7225 2450)(-7050 2450);
WIRE 16 -1 (-7050 2400)(-7050 2350);
WIRE 16 -1 (-7225 2400)(-7050 2400);
WIRE 16 -1 (-7050 2350)(-7050 2300);
WIRE 16 -1 (-7225 2350)(-7050 2350);
WIRE 16 -1 (-7050 2300)(-7050 2250);
WIRE 16 -1 (-7225 2300)(-7050 2300);
WIRE 16 -1 (-7050 2250)(-7050 2200);
WIRE 16 -1 (-7225 2250)(-7050 2250);
WIRE 16 -1 (-7050 2200)(-7050 2150);
WIRE 16 -1 (-7225 2200)(-7050 2200);
WIRE 16 -1 (-7050 2150)(-7050 2100);
WIRE 16 -1 (-7225 2150)(-7050 2150);
WIRE 16 -1 (-7050 2100)(-7050 2050);
WIRE 16 -1 (-7225 2100)(-7050 2100);
WIRE 16 -1 (-7225 2050)(-7050 2050);
WIRE 16 -1 (-7050 2050)(-7050 2000);
WIRE 16 -1 (-7050 2000)(-7050 1950);
WIRE 16 -1 (-7225 2000)(-7050 2000);
WIRE 16 -1 (-7050 1950)(-7050 1900);
WIRE 16 -1 (-7225 1950)(-7050 1950);
WIRE 16 -1 (-7050 1900)(-7050 1850);
WIRE 16 -1 (-7225 1900)(-7050 1900);
WIRE 16 -1 (-7050 1850)(-7050 1800);
WIRE 16 -1 (-7225 1850)(-7050 1850);
WIRE 16 -1 (-7050 1800)(-7050 1750);
WIRE 16 -1 (-7225 1800)(-7050 1800);
WIRE 16 -1 (-7050 1750)(-7050 1700);
WIRE 16 -1 (-7225 1750)(-7050 1750);
WIRE 16 -1 (-7050 1700)(-7050 1650);
WIRE 16 -1 (-7225 1700)(-7050 1700);
WIRE 16 -1 (-7050 1650)(-7050 1600);
WIRE 16 -1 (-7225 1650)(-7050 1650);
WIRE 16 -1 (-7050 1600)(-7050 1550);
WIRE 16 -1 (-7225 1600)(-7050 1600);
WIRE 16 -1 (-7050 1550)(-7050 1500);
WIRE 16 -1 (-7225 1550)(-7050 1550);
WIRE 16 -1 (-7050 1500)(-7050 1450);
WIRE 16 -1 (-7225 1500)(-7050 1500);
WIRE 16 -1 (-7050 1450)(-7050 1400);
WIRE 16 -1 (-7225 1450)(-7050 1450);
WIRE 16 -1 (-7050 1400)(-7050 1350);
WIRE 16 -1 (-7225 1400)(-7050 1400);
WIRE 16 -1 (-7050 1350)(-7050 1300);
WIRE 16 -1 (-7225 1350)(-7050 1350);
WIRE 16 -1 (-7050 1300)(-7050 1250);
WIRE 16 -1 (-7225 1300)(-7050 1300);
WIRE 16 -1 (-7050 1250)(-7050 1200);
WIRE 16 -1 (-7225 1250)(-7050 1250);
WIRE 16 -1 (-7050 1200)(-7050 1150);
WIRE 16 -1 (-7225 1200)(-7050 1200);
WIRE 16 -1 (-7050 1150)(-7050 1100);
WIRE 16 -1 (-7225 1150)(-7050 1150);
WIRE 16 -1 (-7050 1100)(-7050 1050);
WIRE 16 -1 (-7225 1100)(-7050 1100);
WIRE 16 -1 (-7050 1050)(-7050 1000);
WIRE 16 -1 (-7225 1050)(-7050 1050);
WIRE 16 -1 (-7050 1000)(-7050 950);
WIRE 16 -1 (-7225 1000)(-7050 1000);
WIRE 16 -1 (-7050 950)(-7050 900);
WIRE 16 -1 (-7225 950)(-7050 950);
WIRE 16 -1 (-7050 900)(-7050 850);
WIRE 16 -1 (-7225 900)(-7050 900);
WIRE 16 -1 (-7050 850)(-7050 800);
WIRE 16 -1 (-7225 850)(-7050 850);
WIRE 16 -1 (-7050 800)(-7050 750);
WIRE 16 -1 (-7225 800)(-7050 800);
WIRE 16 -1 (-7050 750)(-7050 700);
WIRE 16 -1 (-7225 750)(-7050 750);
WIRE 16 -1 (-7050 700)(-7050 650);
WIRE 16 -1 (-7225 700)(-7050 700);
WIRE 16 -1 (-7050 650)(-7050 600);
WIRE 16 -1 (-7225 650)(-7050 650);
WIRE 16 -1 (-7050 600)(-7050 550);
WIRE 16 -1 (-7225 600)(-7050 600);
WIRE 16 -1 (-7050 475)(-7050 550);
WIRE 16 -1 (-7225 550)(-7050 550);
WIRE 16 -1 (-6475 6350)(-6300 6350);
WIRE 16 -1 (-6475 6350)(-6475 6300);
WIRE 16 -1 (-6300 6300)(-6475 6300);
WIRE 16 -1 (-6475 6300)(-6475 6250);
WIRE 16 -1 (-6475 6250)(-6300 6250);
WIRE 16 -1 (-6475 6250)(-6475 6200);
WIRE 16 -1 (-6475 6200)(-6300 6200);
WIRE 16 -1 (-6475 6200)(-6475 6150);
WIRE 16 -1 (-6475 6150)(-6300 6150);
WIRE 16 -1 (-6475 6150)(-6475 6100);
WIRE 16 -1 (-6475 6100)(-6300 6100);
WIRE 16 -1 (-6475 6100)(-6475 6050);
WIRE 16 -1 (-6300 6050)(-6475 6050);
WIRE 16 -1 (-6475 6050)(-6475 6000);
WIRE 16 -1 (-6475 6000)(-6300 6000);
WIRE 16 -1 (-6475 6000)(-6475 5950);
WIRE 16 -1 (-6475 5950)(-6300 5950);
WIRE 16 -1 (-6475 5950)(-6475 5900);
WIRE 16 -1 (-6475 5900)(-6300 5900);
WIRE 16 -1 (-6475 5900)(-6475 5850);
WIRE 16 -1 (-6475 5850)(-6300 5850);
WIRE 16 -1 (-6475 5850)(-6475 5800);
WIRE 16 -1 (-6300 5800)(-6475 5800);
WIRE 16 -1 (-6475 5800)(-6475 5750);
WIRE 16 -1 (-6475 5750)(-6300 5750);
WIRE 16 -1 (-6475 5750)(-6475 5700);
WIRE 16 -1 (-6475 5700)(-6300 5700);
WIRE 16 -1 (-6475 5700)(-6475 5650);
WIRE 16 -1 (-6475 5650)(-6300 5650);
WIRE 16 -1 (-6475 5650)(-6475 5600);
WIRE 16 -1 (-6475 5600)(-6300 5600);
WIRE 16 -1 (-6475 5600)(-6475 5550);
WIRE 16 -1 (-6300 5550)(-6475 5550);
WIRE 16 -1 (-6475 5550)(-6475 5500);
WIRE 16 -1 (-6475 5500)(-6300 5500);
WIRE 16 -1 (-6475 5500)(-6475 5450);
WIRE 16 -1 (-6475 5450)(-6300 5450);
WIRE 16 -1 (-6475 5450)(-6475 5400);
WIRE 16 -1 (-6475 5400)(-6300 5400);
WIRE 16 -1 (-6475 5400)(-6475 5350);
WIRE 16 -1 (-6475 5350)(-6300 5350);
WIRE 16 -1 (-6475 5350)(-6475 5300);
WIRE 16 -1 (-6300 5300)(-6475 5300);
WIRE 16 -1 (-6475 5300)(-6475 5250);
WIRE 16 -1 (-6475 5250)(-6300 5250);
WIRE 16 -1 (-6475 5250)(-6475 5200);
WIRE 16 -1 (-6475 5200)(-6300 5200);
WIRE 16 -1 (-6475 5200)(-6475 5150);
WIRE 16 -1 (-6475 5150)(-6300 5150);
WIRE 16 -1 (-6475 5150)(-6475 5100);
WIRE 16 -1 (-6475 5100)(-6300 5100);
WIRE 16 -1 (-6475 5100)(-6475 5050);
WIRE 16 -1 (-6300 5050)(-6475 5050);
WIRE 16 -1 (-6475 5050)(-6475 5000);
WIRE 16 -1 (-6475 5000)(-6300 5000);
WIRE 16 -1 (-6475 5000)(-6475 4950);
WIRE 16 -1 (-6475 4950)(-6300 4950);
WIRE 16 -1 (-6475 4950)(-6475 4900);
WIRE 16 -1 (-6475 4900)(-6300 4900);
WIRE 16 -1 (-6475 4900)(-6475 4850);
WIRE 16 -1 (-6475 4850)(-6300 4850);
WIRE 16 -1 (-6475 4850)(-6475 4800);
WIRE 16 -1 (-6300 4800)(-6475 4800);
WIRE 16 -1 (-6475 4800)(-6475 4750);
WIRE 16 -1 (-6475 4750)(-6300 4750);
WIRE 16 -1 (-6475 4750)(-6475 4700);
WIRE 16 -1 (-6475 4700)(-6300 4700);
WIRE 16 -1 (-6475 4700)(-6475 4650);
WIRE 16 -1 (-6475 4650)(-6300 4650);
WIRE 16 -1 (-6475 4650)(-6475 4600);
WIRE 16 -1 (-6475 4600)(-6300 4600);
WIRE 16 -1 (-6475 4600)(-6475 4550);
WIRE 16 -1 (-6300 4550)(-6475 4550);
WIRE 16 -1 (-6475 4550)(-6475 4500);
WIRE 16 -1 (-6475 4500)(-6300 4500);
WIRE 16 -1 (-6475 4500)(-6475 4450);
WIRE 16 -1 (-6475 4450)(-6300 4450);
WIRE 16 -1 (-6475 4450)(-6475 4400);
WIRE 16 -1 (-6475 4400)(-6300 4400);
WIRE 16 -1 (-6475 4400)(-6475 4350);
WIRE 16 -1 (-6475 4350)(-6300 4350);
WIRE 16 -1 (-6475 4350)(-6475 4300);
WIRE 16 -1 (-6300 4300)(-6475 4300);
WIRE 16 -1 (-6475 4300)(-6475 4250);
WIRE 16 -1 (-6475 4250)(-6300 4250);
WIRE 16 -1 (-6475 4250)(-6475 4200);
WIRE 16 -1 (-6475 4200)(-6300 4200);
WIRE 16 -1 (-6475 4200)(-6475 4150);
WIRE 16 -1 (-6475 4150)(-6300 4150);
WIRE 16 -1 (-6475 4150)(-6475 4100);
WIRE 16 -1 (-6475 4100)(-6300 4100);
WIRE 16 -1 (-6475 4100)(-6475 4050);
WIRE 16 -1 (-6475 4050)(-6300 4050);
WIRE 16 -1 (-6475 4050)(-6475 4000);
WIRE 16 -1 (-6300 4000)(-6475 4000);
WIRE 16 -1 (-6475 4000)(-6475 3950);
WIRE 16 -1 (-6475 3950)(-6300 3950);
WIRE 16 -1 (-6475 3950)(-6475 3900);
WIRE 16 -1 (-6475 3900)(-6300 3900);
WIRE 16 -1 (-6475 3900)(-6475 3850);
WIRE 16 -1 (-6475 3850)(-6300 3850);
WIRE 16 -1 (-6475 3850)(-6475 3800);
WIRE 16 -1 (-6475 3800)(-6300 3800);
WIRE 16 -1 (-6475 3800)(-6475 3750);
WIRE 16 -1 (-6300 3750)(-6475 3750);
WIRE 16 -1 (-6475 3750)(-6475 3700);
WIRE 16 -1 (-6475 3700)(-6300 3700);
WIRE 16 -1 (-6475 3700)(-6475 3650);
WIRE 16 -1 (-6475 3650)(-6300 3650);
WIRE 16 -1 (-6475 3650)(-6475 3600);
WIRE 16 -1 (-6475 3600)(-6300 3600);
WIRE 16 -1 (-6475 3600)(-6475 3550);
WIRE 16 -1 (-6475 3550)(-6300 3550);
WIRE 16 -1 (-6475 3550)(-6475 3500);
WIRE 16 -1 (-6300 3500)(-6475 3500);
WIRE 16 -1 (-6475 3500)(-6475 3450);
WIRE 16 -1 (-6475 3450)(-6300 3450);
WIRE 16 -1 (-6475 3450)(-6475 3400);
WIRE 16 -1 (-6475 3400)(-6300 3400);
WIRE 16 -1 (-6475 3400)(-6475 3350);
WIRE 16 -1 (-6475 3350)(-6300 3350);
WIRE 16 -1 (-6475 3350)(-6475 3300);
WIRE 16 -1 (-6475 3300)(-6300 3300);
WIRE 16 -1 (-6475 3300)(-6475 3250);
WIRE 16 -1 (-6300 3250)(-6475 3250);
WIRE 16 -1 (-6475 3250)(-6475 3200);
WIRE 16 -1 (-6475 3200)(-6300 3200);
WIRE 16 -1 (-6475 3200)(-6475 3150);
WIRE 16 -1 (-6475 3150)(-6300 3150);
WIRE 16 -1 (-6475 3150)(-6475 3100);
WIRE 16 -1 (-6475 3100)(-6300 3100);
WIRE 16 -1 (-6475 3100)(-6475 3050);
WIRE 16 -1 (-6475 3050)(-6300 3050);
WIRE 16 -1 (-6475 3050)(-6475 3000);
WIRE 16 -1 (-6300 3000)(-6475 3000);
WIRE 16 -1 (-6475 3000)(-6475 2950);
WIRE 16 -1 (-6475 2950)(-6300 2950);
WIRE 16 -1 (-6475 2950)(-6475 2900);
WIRE 16 -1 (-6475 2900)(-6300 2900);
WIRE 16 -1 (-6475 2900)(-6475 2850);
WIRE 16 -1 (-6475 2850)(-6300 2850);
WIRE 16 -1 (-6475 2850)(-6475 2800);
WIRE 16 -1 (-6475 2800)(-6300 2800);
WIRE 16 -1 (-6475 2800)(-6475 2750);
WIRE 16 -1 (-6300 2750)(-6475 2750);
WIRE 16 -1 (-6475 2750)(-6475 2700);
WIRE 16 -1 (-6475 2700)(-6300 2700);
WIRE 16 -1 (-6475 2700)(-6475 2650);
WIRE 16 -1 (-6475 2650)(-6300 2650);
WIRE 16 -1 (-6475 2650)(-6475 2600);
WIRE 16 -1 (-6475 2600)(-6300 2600);
WIRE 16 -1 (-6475 2600)(-6475 2550);
WIRE 16 -1 (-6475 2550)(-6300 2550);
WIRE 16 -1 (-6475 2550)(-6475 2500);
WIRE 16 -1 (-6300 2500)(-6475 2500);
WIRE 16 -1 (-6475 2500)(-6475 2450);
WIRE 16 -1 (-6475 2450)(-6300 2450);
WIRE 16 -1 (-6475 2450)(-6475 2400);
WIRE 16 -1 (-6475 2400)(-6300 2400);
WIRE 16 -1 (-6475 2400)(-6475 2350);
WIRE 16 -1 (-6475 2350)(-6300 2350);
WIRE 16 -1 (-6475 2350)(-6475 2300);
WIRE 16 -1 (-6475 2300)(-6300 2300);
WIRE 16 -1 (-6475 2300)(-6475 2250);
WIRE 16 -1 (-6300 2250)(-6475 2250);
WIRE 16 -1 (-6475 2250)(-6475 2200);
WIRE 16 -1 (-6475 2200)(-6300 2200);
WIRE 16 -1 (-6475 2200)(-6475 2150);
WIRE 16 -1 (-6475 2150)(-6300 2150);
WIRE 16 -1 (-6475 2150)(-6475 2100);
WIRE 16 -1 (-6475 2100)(-6300 2100);
WIRE 16 -1 (-6475 2100)(-6475 2050);
WIRE 16 -1 (-6475 2050)(-6300 2050);
WIRE 16 -1 (-6475 2050)(-6475 2000);
WIRE 16 -1 (-6475 2000)(-6300 2000);
WIRE 16 -1 (-6475 2000)(-6475 1950);
WIRE 16 -1 (-6300 1950)(-6475 1950);
WIRE 16 -1 (-6475 1950)(-6475 1900);
WIRE 16 -1 (-6475 1900)(-6300 1900);
WIRE 16 -1 (-6475 1900)(-6475 1850);
WIRE 16 -1 (-6475 1850)(-6300 1850);
WIRE 16 -1 (-6475 1850)(-6475 1800);
WIRE 16 -1 (-6475 1800)(-6300 1800);
WIRE 16 -1 (-6475 1800)(-6475 1750);
WIRE 16 -1 (-6475 1750)(-6300 1750);
WIRE 16 -1 (-6475 1750)(-6475 1700);
WIRE 16 -1 (-6300 1700)(-6475 1700);
WIRE 16 -1 (-6475 1700)(-6475 1650);
WIRE 16 -1 (-6475 1650)(-6300 1650);
WIRE 16 -1 (-6475 1650)(-6475 1600);
WIRE 16 -1 (-6475 1600)(-6300 1600);
WIRE 16 -1 (-6475 1600)(-6475 1550);
WIRE 16 -1 (-6475 1550)(-6300 1550);
WIRE 16 -1 (-6475 1550)(-6475 1500);
WIRE 16 -1 (-6475 1500)(-6300 1500);
WIRE 16 -1 (-6475 1500)(-6475 1450);
WIRE 16 -1 (-6300 1450)(-6475 1450);
WIRE 16 -1 (-6475 1450)(-6475 1400);
WIRE 16 -1 (-6475 1400)(-6300 1400);
WIRE 16 -1 (-6475 1400)(-6475 1350);
WIRE 16 -1 (-6475 1350)(-6300 1350);
WIRE 16 -1 (-6475 1350)(-6475 1300);
WIRE 16 -1 (-6475 1300)(-6300 1300);
WIRE 16 -1 (-6475 1300)(-6475 1250);
WIRE 16 -1 (-6475 1250)(-6300 1250);
WIRE 16 -1 (-6475 1250)(-6475 1200);
WIRE 16 -1 (-6300 1200)(-6475 1200);
WIRE 16 -1 (-6475 1200)(-6475 1150);
WIRE 16 -1 (-6475 1150)(-6300 1150);
WIRE 16 -1 (-6475 1150)(-6475 1100);
WIRE 16 -1 (-6475 1100)(-6300 1100);
WIRE 16 -1 (-6475 1100)(-6475 1050);
WIRE 16 -1 (-6475 1050)(-6300 1050);
WIRE 16 -1 (-6475 1050)(-6475 1000);
WIRE 16 -1 (-6475 1000)(-6300 1000);
WIRE 16 -1 (-6475 1000)(-6475 950);
WIRE 16 -1 (-6300 950)(-6475 950);
WIRE 16 -1 (-6475 950)(-6475 900);
WIRE 16 -1 (-6475 900)(-6300 900);
WIRE 16 -1 (-6475 900)(-6475 850);
WIRE 16 -1 (-6475 850)(-6300 850);
WIRE 16 -1 (-6475 850)(-6475 800);
WIRE 16 -1 (-6475 800)(-6300 800);
WIRE 16 -1 (-6475 800)(-6475 750);
WIRE 16 -1 (-6475 750)(-6300 750);
WIRE 16 -1 (-6475 750)(-6475 700);
WIRE 16 -1 (-6300 700)(-6475 700);
WIRE 16 -1 (-6475 700)(-6475 650);
WIRE 16 -1 (-6475 650)(-6300 650);
WIRE 16 -1 (-6475 650)(-6475 600);
WIRE 16 -1 (-6475 600)(-6300 600);
WIRE 16 -1 (-6475 600)(-6475 550);
WIRE 16 -1 (-6475 550)(-6300 550);
WIRE 16 -1 (-6475 550)(-6475 500);
WIRE 16 -1 (-6475 500)(-6300 500);
WIRE 16 -1 (-6475 475)(-6475 500);
WIRE 16 -1 (-5200 6300)(-5025 6300);
WIRE 16 -1 (-5025 6300)(-5025 6250);
WIRE 16 -1 (-5025 6250)(-5025 6200);
WIRE 16 -1 (-5200 6250)(-5025 6250);
WIRE 16 -1 (-5025 6200)(-5025 6150);
WIRE 16 -1 (-5200 6200)(-5025 6200);
WIRE 16 -1 (-5200 6150)(-5025 6150);
WIRE 16 -1 (-5025 6150)(-5025 6100);
WIRE 16 -1 (-5025 6100)(-5025 6050);
WIRE 16 -1 (-5200 6100)(-5025 6100);
WIRE 16 -1 (-5025 6050)(-5025 6000);
WIRE 16 -1 (-5200 6050)(-5025 6050);
WIRE 16 -1 (-5025 6000)(-5025 5950);
WIRE 16 -1 (-5200 6000)(-5025 6000);
WIRE 16 -1 (-5025 5950)(-5025 5900);
WIRE 16 -1 (-5200 5950)(-5025 5950);
WIRE 16 -1 (-5025 5900)(-5025 5850);
WIRE 16 -1 (-5200 5900)(-5025 5900);
WIRE 16 -1 (-5025 5850)(-5025 5800);
WIRE 16 -1 (-5200 5850)(-5025 5850);
WIRE 16 -1 (-5025 5800)(-5025 5750);
WIRE 16 -1 (-5200 5800)(-5025 5800);
WIRE 16 -1 (-5025 5750)(-5025 5700);
WIRE 16 -1 (-5200 5750)(-5025 5750);
WIRE 16 -1 (-5025 5700)(-5025 5650);
WIRE 16 -1 (-5200 5700)(-5025 5700);
WIRE 16 -1 (-5025 5650)(-5025 5600);
WIRE 16 -1 (-5200 5650)(-5025 5650);
WIRE 16 -1 (-5025 5600)(-5025 5550);
WIRE 16 -1 (-5200 5600)(-5025 5600);
WIRE 16 -1 (-5025 5550)(-5025 5500);
WIRE 16 -1 (-5200 5550)(-5025 5550);
WIRE 16 -1 (-5025 5500)(-5025 5450);
WIRE 16 -1 (-5200 5500)(-5025 5500);
WIRE 16 -1 (-5025 5450)(-5025 5400);
WIRE 16 -1 (-5200 5450)(-5025 5450);
WIRE 16 -1 (-5025 5400)(-5025 5350);
WIRE 16 -1 (-5200 5400)(-5025 5400);
WIRE 16 -1 (-5025 5350)(-5025 5300);
WIRE 16 -1 (-5200 5350)(-5025 5350);
WIRE 16 -1 (-5025 5300)(-5025 5250);
WIRE 16 -1 (-5200 5300)(-5025 5300);
WIRE 16 -1 (-5025 5250)(-5025 5200);
WIRE 16 -1 (-5200 5250)(-5025 5250);
WIRE 16 -1 (-5025 5200)(-5025 5150);
WIRE 16 -1 (-5200 5200)(-5025 5200);
WIRE 16 -1 (-5025 5150)(-5025 5100);
WIRE 16 -1 (-5200 5150)(-5025 5150);
WIRE 16 -1 (-5025 5100)(-5025 5050);
WIRE 16 -1 (-5200 5100)(-5025 5100);
WIRE 16 -1 (-5025 5050)(-5025 5000);
WIRE 16 -1 (-5200 5050)(-5025 5050);
WIRE 16 -1 (-5025 5000)(-5025 4950);
WIRE 16 -1 (-5200 5000)(-5025 5000);
WIRE 16 -1 (-5025 4950)(-5025 4900);
WIRE 16 -1 (-5200 4950)(-5025 4950);
WIRE 16 -1 (-5025 4900)(-5025 4850);
WIRE 16 -1 (-5200 4900)(-5025 4900);
WIRE 16 -1 (-5025 4850)(-5025 4800);
WIRE 16 -1 (-5200 4850)(-5025 4850);
WIRE 16 -1 (-5025 4800)(-5025 4750);
WIRE 16 -1 (-5200 4800)(-5025 4800);
WIRE 16 -1 (-5025 4750)(-5025 4700);
WIRE 16 -1 (-5200 4750)(-5025 4750);
WIRE 16 -1 (-5025 4700)(-5025 4650);
WIRE 16 -1 (-5200 4700)(-5025 4700);
WIRE 16 -1 (-5025 4650)(-5025 4600);
WIRE 16 -1 (-5200 4650)(-5025 4650);
WIRE 16 -1 (-5025 4600)(-5025 4550);
WIRE 16 -1 (-5200 4600)(-5025 4600);
WIRE 16 -1 (-5025 4550)(-5025 4500);
WIRE 16 -1 (-5200 4550)(-5025 4550);
WIRE 16 -1 (-5025 4500)(-5025 4450);
WIRE 16 -1 (-5200 4500)(-5025 4500);
WIRE 16 -1 (-5025 4450)(-5025 4400);
WIRE 16 -1 (-5200 4450)(-5025 4450);
WIRE 16 -1 (-5025 4400)(-5025 4350);
WIRE 16 -1 (-5200 4400)(-5025 4400);
WIRE 16 -1 (-5025 4350)(-5025 4300);
WIRE 16 -1 (-5200 4350)(-5025 4350);
WIRE 16 -1 (-5025 4300)(-5025 4250);
WIRE 16 -1 (-5200 4300)(-5025 4300);
WIRE 16 -1 (-5025 4250)(-5025 4200);
WIRE 16 -1 (-5200 4250)(-5025 4250);
WIRE 16 -1 (-5025 4200)(-5025 4150);
WIRE 16 -1 (-5200 4200)(-5025 4200);
WIRE 16 -1 (-5025 4150)(-5025 4100);
WIRE 16 -1 (-5200 4150)(-5025 4150);
WIRE 16 -1 (-5200 4100)(-5025 4100);
WIRE 16 -1 (-5025 4100)(-5025 4050);
WIRE 16 -1 (-5025 4050)(-5025 4000);
WIRE 16 -1 (-5200 4050)(-5025 4050);
WIRE 16 -1 (-5025 4000)(-5025 3950);
WIRE 16 -1 (-5200 4000)(-5025 4000);
WIRE 16 -1 (-5025 3950)(-5025 3900);
WIRE 16 -1 (-5200 3950)(-5025 3950);
WIRE 16 -1 (-5025 3900)(-5025 3850);
WIRE 16 -1 (-5200 3900)(-5025 3900);
WIRE 16 -1 (-5025 3850)(-5025 3800);
WIRE 16 -1 (-5200 3850)(-5025 3850);
WIRE 16 -1 (-5025 3800)(-5025 3750);
WIRE 16 -1 (-5200 3800)(-5025 3800);
WIRE 16 -1 (-5025 3750)(-5025 3700);
WIRE 16 -1 (-5200 3750)(-5025 3750);
WIRE 16 -1 (-5025 3700)(-5025 3650);
WIRE 16 -1 (-5200 3700)(-5025 3700);
WIRE 16 -1 (-5025 3650)(-5025 3600);
WIRE 16 -1 (-5200 3650)(-5025 3650);
WIRE 16 -1 (-5025 3600)(-5025 3550);
WIRE 16 -1 (-5200 3600)(-5025 3600);
WIRE 16 -1 (-5025 3550)(-5025 3500);
WIRE 16 -1 (-5200 3550)(-5025 3550);
WIRE 16 -1 (-5025 3500)(-5025 3450);
WIRE 16 -1 (-5200 3500)(-5025 3500);
WIRE 16 -1 (-5025 3450)(-5025 3400);
WIRE 16 -1 (-5200 3450)(-5025 3450);
WIRE 16 -1 (-5025 3400)(-5025 3350);
WIRE 16 -1 (-5200 3400)(-5025 3400);
WIRE 16 -1 (-5025 3350)(-5025 3300);
WIRE 16 -1 (-5200 3350)(-5025 3350);
WIRE 16 -1 (-5025 3300)(-5025 3250);
WIRE 16 -1 (-5200 3300)(-5025 3300);
WIRE 16 -1 (-5025 3250)(-5025 3200);
WIRE 16 -1 (-5200 3250)(-5025 3250);
WIRE 16 -1 (-5025 3200)(-5025 3150);
WIRE 16 -1 (-5200 3200)(-5025 3200);
WIRE 16 -1 (-5025 3150)(-5025 3100);
WIRE 16 -1 (-5200 3150)(-5025 3150);
WIRE 16 -1 (-5025 3100)(-5025 3050);
WIRE 16 -1 (-5200 3100)(-5025 3100);
WIRE 16 -1 (-5025 3050)(-5025 3000);
WIRE 16 -1 (-5200 3050)(-5025 3050);
WIRE 16 -1 (-5025 3000)(-5025 2950);
WIRE 16 -1 (-5200 3000)(-5025 3000);
WIRE 16 -1 (-5025 2950)(-5025 2900);
WIRE 16 -1 (-5200 2950)(-5025 2950);
WIRE 16 -1 (-5025 2900)(-5025 2850);
WIRE 16 -1 (-5200 2900)(-5025 2900);
WIRE 16 -1 (-5025 2850)(-5025 2800);
WIRE 16 -1 (-5200 2850)(-5025 2850);
WIRE 16 -1 (-5025 2800)(-5025 2750);
WIRE 16 -1 (-5200 2800)(-5025 2800);
WIRE 16 -1 (-5025 2750)(-5025 2700);
WIRE 16 -1 (-5200 2750)(-5025 2750);
WIRE 16 -1 (-5025 2700)(-5025 2650);
WIRE 16 -1 (-5200 2700)(-5025 2700);
WIRE 16 -1 (-5025 2650)(-5025 2600);
WIRE 16 -1 (-5200 2650)(-5025 2650);
WIRE 16 -1 (-5025 2600)(-5025 2550);
WIRE 16 -1 (-5200 2600)(-5025 2600);
WIRE 16 -1 (-5025 2550)(-5025 2500);
WIRE 16 -1 (-5200 2550)(-5025 2550);
WIRE 16 -1 (-5025 2500)(-5025 2450);
WIRE 16 -1 (-5200 2500)(-5025 2500);
WIRE 16 -1 (-5025 2450)(-5025 2400);
WIRE 16 -1 (-5200 2450)(-5025 2450);
WIRE 16 -1 (-5025 2400)(-5025 2350);
WIRE 16 -1 (-5200 2400)(-5025 2400);
WIRE 16 -1 (-5025 2350)(-5025 2300);
WIRE 16 -1 (-5200 2350)(-5025 2350);
WIRE 16 -1 (-5025 2300)(-5025 2250);
WIRE 16 -1 (-5200 2300)(-5025 2300);
WIRE 16 -1 (-5025 2250)(-5025 2200);
WIRE 16 -1 (-5200 2250)(-5025 2250);
WIRE 16 -1 (-5025 2200)(-5025 2150);
WIRE 16 -1 (-5200 2200)(-5025 2200);
WIRE 16 -1 (-5025 2150)(-5025 2100);
WIRE 16 -1 (-5200 2150)(-5025 2150);
WIRE 16 -1 (-5025 2100)(-5025 2050);
WIRE 16 -1 (-5200 2100)(-5025 2100);
WIRE 16 -1 (-5200 2050)(-5025 2050);
WIRE 16 -1 (-5025 2050)(-5025 2000);
WIRE 16 -1 (-5025 2000)(-5025 1950);
WIRE 16 -1 (-5200 2000)(-5025 2000);
WIRE 16 -1 (-5025 1950)(-5025 1900);
WIRE 16 -1 (-5200 1950)(-5025 1950);
WIRE 16 -1 (-5025 1900)(-5025 1850);
WIRE 16 -1 (-5200 1900)(-5025 1900);
WIRE 16 -1 (-5025 1850)(-5025 1800);
WIRE 16 -1 (-5200 1850)(-5025 1850);
WIRE 16 -1 (-5025 1800)(-5025 1750);
WIRE 16 -1 (-5200 1800)(-5025 1800);
WIRE 16 -1 (-5025 1750)(-5025 1700);
WIRE 16 -1 (-5200 1750)(-5025 1750);
WIRE 16 -1 (-5025 1700)(-5025 1650);
WIRE 16 -1 (-5200 1700)(-5025 1700);
WIRE 16 -1 (-5025 1650)(-5025 1600);
WIRE 16 -1 (-5200 1650)(-5025 1650);
WIRE 16 -1 (-5025 1600)(-5025 1550);
WIRE 16 -1 (-5200 1600)(-5025 1600);
WIRE 16 -1 (-5025 1550)(-5025 1500);
WIRE 16 -1 (-5200 1550)(-5025 1550);
WIRE 16 -1 (-5025 1500)(-5025 1450);
WIRE 16 -1 (-5200 1500)(-5025 1500);
WIRE 16 -1 (-5025 1450)(-5025 1400);
WIRE 16 -1 (-5200 1450)(-5025 1450);
WIRE 16 -1 (-5025 1400)(-5025 1350);
WIRE 16 -1 (-5200 1400)(-5025 1400);
WIRE 16 -1 (-5025 1350)(-5025 1300);
WIRE 16 -1 (-5200 1350)(-5025 1350);
WIRE 16 -1 (-5025 1300)(-5025 1250);
WIRE 16 -1 (-5200 1300)(-5025 1300);
WIRE 16 -1 (-5025 1250)(-5025 1200);
WIRE 16 -1 (-5200 1250)(-5025 1250);
WIRE 16 -1 (-5025 1200)(-5025 1150);
WIRE 16 -1 (-5200 1200)(-5025 1200);
WIRE 16 -1 (-5025 1150)(-5025 1100);
WIRE 16 -1 (-5200 1150)(-5025 1150);
WIRE 16 -1 (-5025 1100)(-5025 1050);
WIRE 16 -1 (-5200 1100)(-5025 1100);
WIRE 16 -1 (-5025 1050)(-5025 1000);
WIRE 16 -1 (-5200 1050)(-5025 1050);
WIRE 16 -1 (-5025 1000)(-5025 950);
WIRE 16 -1 (-5200 1000)(-5025 1000);
WIRE 16 -1 (-5025 950)(-5025 900);
WIRE 16 -1 (-5200 950)(-5025 950);
WIRE 16 -1 (-5025 900)(-5025 850);
WIRE 16 -1 (-5200 900)(-5025 900);
WIRE 16 -1 (-5025 850)(-5025 800);
WIRE 16 -1 (-5200 850)(-5025 850);
WIRE 16 -1 (-5025 800)(-5025 750);
WIRE 16 -1 (-5200 800)(-5025 800);
WIRE 16 -1 (-5025 750)(-5025 700);
WIRE 16 -1 (-5200 750)(-5025 750);
WIRE 16 -1 (-5025 700)(-5025 650);
WIRE 16 -1 (-5200 700)(-5025 700);
WIRE 16 -1 (-5025 650)(-5025 600);
WIRE 16 -1 (-5200 650)(-5025 650);
WIRE 16 -1 (-5025 600)(-5025 550);
WIRE 16 -1 (-5200 600)(-5025 600);
WIRE 16 -1 (-5025 550)(-5025 500);
WIRE 16 -1 (-5200 550)(-5025 550);
WIRE 16 -1 (-5200 500)(-5025 500);
WIRE 16 -1 (-5025 500)(-5025 475);
WIRE 16 -1 (-4400 6275)(-4225 6275);
WIRE 16 -1 (-4400 6275)(-4400 6225);
WIRE 16 -1 (-4225 6225)(-4400 6225);
WIRE 16 -1 (-4400 6225)(-4400 6175);
WIRE 16 -1 (-4400 6175)(-4225 6175);
WIRE 16 -1 (-4400 6175)(-4400 6125);
WIRE 16 -1 (-4400 6125)(-4225 6125);
WIRE 16 -1 (-4400 6125)(-4400 6075);
WIRE 16 -1 (-4400 6075)(-4225 6075);
WIRE 16 -1 (-4400 6075)(-4400 6025);
WIRE 16 -1 (-4400 6025)(-4225 6025);
WIRE 16 -1 (-4400 6025)(-4400 5975);
WIRE 16 -1 (-4225 5975)(-4400 5975);
WIRE 16 -1 (-4400 5975)(-4400 5925);
WIRE 16 -1 (-4400 5925)(-4225 5925);
WIRE 16 -1 (-4400 5925)(-4400 5875);
WIRE 16 -1 (-4400 5875)(-4225 5875);
WIRE 16 -1 (-4400 5875)(-4400 5825);
WIRE 16 -1 (-4400 5825)(-4225 5825);
WIRE 16 -1 (-4400 5825)(-4400 5775);
WIRE 16 -1 (-4400 5775)(-4225 5775);
WIRE 16 -1 (-4400 5775)(-4400 5725);
WIRE 16 -1 (-4225 5725)(-4400 5725);
WIRE 16 -1 (-4400 5725)(-4400 5675);
WIRE 16 -1 (-4400 5675)(-4225 5675);
WIRE 16 -1 (-4400 5675)(-4400 5625);
WIRE 16 -1 (-4400 5625)(-4225 5625);
WIRE 16 -1 (-4400 5625)(-4400 5575);
WIRE 16 -1 (-4400 5575)(-4225 5575);
WIRE 16 -1 (-4400 5575)(-4400 5525);
WIRE 16 -1 (-4400 5525)(-4225 5525);
WIRE 16 -1 (-4400 5525)(-4400 5475);
WIRE 16 -1 (-4225 5475)(-4400 5475);
WIRE 16 -1 (-4400 5475)(-4400 5425);
WIRE 16 -1 (-4400 5425)(-4225 5425);
WIRE 16 -1 (-4400 5425)(-4400 5375);
WIRE 16 -1 (-4400 5375)(-4225 5375);
WIRE 16 -1 (-4400 5375)(-4400 5325);
WIRE 16 -1 (-4400 5325)(-4225 5325);
WIRE 16 -1 (-4400 5325)(-4400 5275);
WIRE 16 -1 (-4400 5275)(-4225 5275);
WIRE 16 -1 (-4400 5275)(-4400 5225);
WIRE 16 -1 (-4225 5225)(-4400 5225);
WIRE 16 -1 (-4400 5225)(-4400 5175);
WIRE 16 -1 (-4400 5175)(-4225 5175);
WIRE 16 -1 (-4400 5175)(-4400 5125);
WIRE 16 -1 (-4400 5125)(-4225 5125);
WIRE 16 -1 (-4400 5125)(-4400 5075);
WIRE 16 -1 (-4400 5075)(-4225 5075);
WIRE 16 -1 (-4400 5075)(-4400 5025);
WIRE 16 -1 (-4400 5025)(-4225 5025);
WIRE 16 -1 (-4400 5025)(-4400 4975);
WIRE 16 -1 (-4225 4975)(-4400 4975);
WIRE 16 -1 (-4400 4975)(-4400 4925);
WIRE 16 -1 (-4400 4925)(-4225 4925);
WIRE 16 -1 (-4400 4925)(-4400 4875);
WIRE 16 -1 (-4400 4875)(-4225 4875);
WIRE 16 -1 (-4400 4875)(-4400 4825);
WIRE 16 -1 (-4400 4825)(-4225 4825);
WIRE 16 -1 (-4400 4825)(-4400 4775);
WIRE 16 -1 (-4400 4775)(-4225 4775);
WIRE 16 -1 (-4400 4775)(-4400 4725);
WIRE 16 -1 (-4225 4725)(-4400 4725);
WIRE 16 -1 (-4400 4725)(-4400 4675);
WIRE 16 -1 (-4400 4675)(-4225 4675);
WIRE 16 -1 (-4400 4675)(-4400 4625);
WIRE 16 -1 (-4400 4625)(-4225 4625);
WIRE 16 -1 (-4400 4625)(-4400 4575);
WIRE 16 -1 (-4400 4575)(-4225 4575);
WIRE 16 -1 (-4400 4575)(-4400 4525);
WIRE 16 -1 (-4400 4525)(-4225 4525);
WIRE 16 -1 (-4400 4525)(-4400 4475);
WIRE 16 -1 (-4225 4475)(-4400 4475);
WIRE 16 -1 (-4400 4475)(-4400 4425);
WIRE 16 -1 (-4400 4425)(-4225 4425);
WIRE 16 -1 (-4400 4425)(-4400 4375);
WIRE 16 -1 (-4400 4375)(-4225 4375);
WIRE 16 -1 (-4400 4375)(-4400 4325);
WIRE 16 -1 (-4400 4325)(-4225 4325);
WIRE 16 -1 (-4400 4325)(-4400 4275);
WIRE 16 -1 (-4400 4275)(-4225 4275);
WIRE 16 -1 (-4400 4275)(-4400 4225);
WIRE 16 -1 (-4225 4225)(-4400 4225);
WIRE 16 -1 (-4400 4225)(-4400 4175);
WIRE 16 -1 (-4400 4175)(-4225 4175);
WIRE 16 -1 (-4400 4175)(-4400 4125);
WIRE 16 -1 (-4400 4125)(-4225 4125);
WIRE 16 -1 (-4400 4125)(-4400 4075);
WIRE 16 -1 (-4400 4075)(-4225 4075);
WIRE 16 -1 (-4400 4075)(-4400 4025);
WIRE 16 -1 (-4400 4025)(-4225 4025);
WIRE 16 -1 (-4400 4025)(-4400 3975);
WIRE 16 -1 (-4400 3975)(-4225 3975);
WIRE 16 -1 (-4400 3975)(-4400 3925);
WIRE 16 -1 (-4225 3925)(-4400 3925);
WIRE 16 -1 (-4400 3925)(-4400 3875);
WIRE 16 -1 (-4400 3875)(-4225 3875);
WIRE 16 -1 (-4400 3875)(-4400 3825);
WIRE 16 -1 (-4400 3825)(-4225 3825);
WIRE 16 -1 (-4400 3825)(-4400 3775);
WIRE 16 -1 (-4400 3775)(-4225 3775);
WIRE 16 -1 (-4400 3775)(-4400 3725);
WIRE 16 -1 (-4400 3725)(-4225 3725);
WIRE 16 -1 (-4400 3725)(-4400 3675);
WIRE 16 -1 (-4225 3675)(-4400 3675);
WIRE 16 -1 (-4400 3675)(-4400 3625);
WIRE 16 -1 (-4400 3625)(-4225 3625);
WIRE 16 -1 (-4400 3625)(-4400 3575);
WIRE 16 -1 (-4400 3575)(-4225 3575);
WIRE 16 -1 (-4400 3575)(-4400 3525);
WIRE 16 -1 (-4400 3525)(-4225 3525);
WIRE 16 -1 (-4400 3525)(-4400 3475);
WIRE 16 -1 (-4400 3475)(-4225 3475);
WIRE 16 -1 (-4400 3475)(-4400 3425);
WIRE 16 -1 (-4225 3425)(-4400 3425);
WIRE 16 -1 (-4400 3425)(-4400 3375);
WIRE 16 -1 (-4400 3375)(-4225 3375);
WIRE 16 -1 (-4400 3375)(-4400 3325);
WIRE 16 -1 (-4400 3325)(-4225 3325);
WIRE 16 -1 (-4400 3325)(-4400 3275);
WIRE 16 -1 (-4400 3275)(-4225 3275);
WIRE 16 -1 (-4400 3275)(-4400 3225);
WIRE 16 -1 (-4400 3225)(-4225 3225);
WIRE 16 -1 (-4400 3225)(-4400 3175);
WIRE 16 -1 (-4225 3175)(-4400 3175);
WIRE 16 -1 (-4400 3175)(-4400 3125);
WIRE 16 -1 (-4400 3125)(-4225 3125);
WIRE 16 -1 (-4400 3125)(-4400 3075);
WIRE 16 -1 (-4400 3075)(-4225 3075);
WIRE 16 -1 (-4400 3075)(-4400 3025);
WIRE 16 -1 (-4400 3025)(-4225 3025);
WIRE 16 -1 (-4400 3025)(-4400 2975);
WIRE 16 -1 (-4400 2975)(-4225 2975);
WIRE 16 -1 (-4400 2975)(-4400 2925);
WIRE 16 -1 (-4225 2925)(-4400 2925);
WIRE 16 -1 (-4400 2925)(-4400 2875);
WIRE 16 -1 (-4400 2875)(-4225 2875);
WIRE 16 -1 (-4400 2875)(-4400 2825);
WIRE 16 -1 (-4400 2825)(-4225 2825);
WIRE 16 -1 (-4400 2825)(-4400 2775);
WIRE 16 -1 (-4400 2775)(-4225 2775);
WIRE 16 -1 (-4400 2775)(-4400 2725);
WIRE 16 -1 (-4400 2725)(-4225 2725);
WIRE 16 -1 (-4400 2725)(-4400 2675);
WIRE 16 -1 (-4225 2675)(-4400 2675);
WIRE 16 -1 (-4400 2675)(-4400 2625);
WIRE 16 -1 (-4400 2625)(-4225 2625);
WIRE 16 -1 (-4400 2625)(-4400 2575);
WIRE 16 -1 (-4400 2575)(-4225 2575);
WIRE 16 -1 (-4400 2575)(-4400 2525);
WIRE 16 -1 (-4400 2525)(-4225 2525);
WIRE 16 -1 (-4400 2525)(-4400 2475);
WIRE 16 -1 (-4400 2475)(-4225 2475);
WIRE 16 -1 (-4400 2475)(-4400 2425);
WIRE 16 -1 (-4225 2425)(-4400 2425);
WIRE 16 -1 (-4400 2425)(-4400 2375);
WIRE 16 -1 (-4400 2375)(-4225 2375);
WIRE 16 -1 (-4400 2375)(-4400 2325);
WIRE 16 -1 (-4400 2325)(-4225 2325);
WIRE 16 -1 (-4400 2325)(-4400 2275);
WIRE 16 -1 (-4400 2275)(-4225 2275);
WIRE 16 -1 (-4400 2275)(-4400 2225);
WIRE 16 -1 (-4400 2225)(-4225 2225);
WIRE 16 -1 (-4400 2225)(-4400 2175);
WIRE 16 -1 (-4225 2175)(-4400 2175);
WIRE 16 -1 (-4400 2175)(-4400 2125);
WIRE 16 -1 (-4400 2125)(-4225 2125);
WIRE 16 -1 (-4400 2125)(-4400 2075);
WIRE 16 -1 (-4400 2075)(-4225 2075);
WIRE 16 -1 (-4400 2075)(-4400 2025);
WIRE 16 -1 (-4400 2025)(-4225 2025);
WIRE 16 -1 (-4400 2025)(-4400 1975);
WIRE 16 -1 (-4400 1975)(-4225 1975);
WIRE 16 -1 (-4400 1975)(-4400 1925);
WIRE 16 -1 (-4400 1925)(-4225 1925);
WIRE 16 -1 (-4400 1925)(-4400 1875);
WIRE 16 -1 (-4225 1875)(-4400 1875);
WIRE 16 -1 (-4400 1875)(-4400 1825);
WIRE 16 -1 (-4400 1825)(-4225 1825);
WIRE 16 -1 (-4400 1825)(-4400 1775);
WIRE 16 -1 (-4400 1775)(-4225 1775);
WIRE 16 -1 (-4400 1775)(-4400 1725);
WIRE 16 -1 (-4400 1725)(-4225 1725);
WIRE 16 -1 (-4400 1725)(-4400 1675);
WIRE 16 -1 (-4400 1675)(-4225 1675);
WIRE 16 -1 (-4400 1675)(-4400 1625);
WIRE 16 -1 (-4225 1625)(-4400 1625);
WIRE 16 -1 (-4400 1625)(-4400 1575);
WIRE 16 -1 (-4400 1575)(-4225 1575);
WIRE 16 -1 (-4400 1575)(-4400 1525);
WIRE 16 -1 (-4400 1525)(-4225 1525);
WIRE 16 -1 (-4400 1525)(-4400 1475);
WIRE 16 -1 (-4400 1475)(-4225 1475);
WIRE 16 -1 (-4400 1475)(-4400 1425);
WIRE 16 -1 (-4400 1425)(-4225 1425);
WIRE 16 -1 (-4400 1425)(-4400 1375);
WIRE 16 -1 (-4225 1375)(-4400 1375);
WIRE 16 -1 (-4400 1375)(-4400 1325);
WIRE 16 -1 (-4400 1325)(-4225 1325);
WIRE 16 -1 (-4400 1325)(-4400 1275);
WIRE 16 -1 (-4400 1275)(-4225 1275);
WIRE 16 -1 (-4400 1275)(-4400 1225);
WIRE 16 -1 (-4400 1225)(-4225 1225);
WIRE 16 -1 (-4400 1225)(-4400 1175);
WIRE 16 -1 (-4400 1175)(-4225 1175);
WIRE 16 -1 (-4400 1175)(-4400 1125);
WIRE 16 -1 (-4225 1125)(-4400 1125);
WIRE 16 -1 (-4400 1125)(-4400 1075);
WIRE 16 -1 (-4400 1075)(-4225 1075);
WIRE 16 -1 (-4400 1075)(-4400 1025);
WIRE 16 -1 (-4400 1025)(-4225 1025);
WIRE 16 -1 (-4400 1025)(-4400 975);
WIRE 16 -1 (-4400 975)(-4225 975);
WIRE 16 -1 (-4400 975)(-4400 925);
WIRE 16 -1 (-4400 925)(-4225 925);
WIRE 16 -1 (-4400 925)(-4400 875);
WIRE 16 -1 (-4225 875)(-4400 875);
WIRE 16 -1 (-4400 875)(-4400 825);
WIRE 16 -1 (-4400 825)(-4225 825);
WIRE 16 -1 (-4400 825)(-4400 775);
WIRE 16 -1 (-4400 775)(-4225 775);
WIRE 16 -1 (-4400 775)(-4400 725);
WIRE 16 -1 (-4400 725)(-4225 725);
WIRE 16 -1 (-4400 725)(-4400 675);
WIRE 16 -1 (-4400 675)(-4225 675);
WIRE 16 -1 (-4400 675)(-4400 625);
WIRE 16 -1 (-4225 625)(-4400 625);
WIRE 16 -1 (-4400 625)(-4400 575);
WIRE 16 -1 (-4400 575)(-4225 575);
WIRE 16 -1 (-4400 575)(-4400 475);
WIRE 16 -1 (-3125 6375)(-2950 6375);
WIRE 16 -1 (-2950 6375)(-2950 6325);
WIRE 16 -1 (-2950 6325)(-2950 6275);
WIRE 16 -1 (-3125 6325)(-2950 6325);
WIRE 16 -1 (-2950 6275)(-2950 6225);
WIRE 16 -1 (-3125 6275)(-2950 6275);
WIRE 16 -1 (-2950 6225)(-2950 6175);
WIRE 16 -1 (-3125 6225)(-2950 6225);
WIRE 16 -1 (-3125 6175)(-2950 6175);
WIRE 16 -1 (-2950 6175)(-2950 6125);
WIRE 16 -1 (-2950 6125)(-2950 6075);
WIRE 16 -1 (-3125 6125)(-2950 6125);
WIRE 16 -1 (-2950 6075)(-2950 6025);
WIRE 16 -1 (-3125 6075)(-2950 6075);
WIRE 16 -1 (-2950 6025)(-2950 5975);
WIRE 16 -1 (-3125 6025)(-2950 6025);
WIRE 16 -1 (-2950 5975)(-2950 5925);
WIRE 16 -1 (-3125 5975)(-2950 5975);
WIRE 16 -1 (-2950 5925)(-2950 5875);
WIRE 16 -1 (-3125 5925)(-2950 5925);
WIRE 16 -1 (-2950 5875)(-2950 5825);
WIRE 16 -1 (-3125 5875)(-2950 5875);
WIRE 16 -1 (-2950 5825)(-2950 5775);
WIRE 16 -1 (-3125 5825)(-2950 5825);
WIRE 16 -1 (-2950 5775)(-2950 5725);
WIRE 16 -1 (-3125 5775)(-2950 5775);
WIRE 16 -1 (-2950 5725)(-2950 5675);
WIRE 16 -1 (-3125 5725)(-2950 5725);
WIRE 16 -1 (-2950 5675)(-2950 5625);
WIRE 16 -1 (-3125 5675)(-2950 5675);
WIRE 16 -1 (-2950 5625)(-2950 5575);
WIRE 16 -1 (-3125 5625)(-2950 5625);
WIRE 16 -1 (-2950 5575)(-2950 5525);
WIRE 16 -1 (-3125 5575)(-2950 5575);
WIRE 16 -1 (-2950 5525)(-2950 5475);
WIRE 16 -1 (-3125 5525)(-2950 5525);
WIRE 16 -1 (-2950 5475)(-2950 5425);
WIRE 16 -1 (-3125 5475)(-2950 5475);
WIRE 16 -1 (-2950 5425)(-2950 5375);
WIRE 16 -1 (-3125 5425)(-2950 5425);
WIRE 16 -1 (-2950 5375)(-2950 5325);
WIRE 16 -1 (-3125 5375)(-2950 5375);
WIRE 16 -1 (-2950 5325)(-2950 5275);
WIRE 16 -1 (-3125 5325)(-2950 5325);
WIRE 16 -1 (-2950 5275)(-2950 5225);
WIRE 16 -1 (-3125 5275)(-2950 5275);
WIRE 16 -1 (-2950 5225)(-2950 5175);
WIRE 16 -1 (-3125 5225)(-2950 5225);
WIRE 16 -1 (-2950 5175)(-2950 5125);
WIRE 16 -1 (-3125 5175)(-2950 5175);
WIRE 16 -1 (-2950 5125)(-2950 5075);
WIRE 16 -1 (-3125 5125)(-2950 5125);
WIRE 16 -1 (-2950 5075)(-2950 5025);
WIRE 16 -1 (-3125 5075)(-2950 5075);
WIRE 16 -1 (-2950 5025)(-2950 4975);
WIRE 16 -1 (-3125 5025)(-2950 5025);
WIRE 16 -1 (-2950 4975)(-2950 4925);
WIRE 16 -1 (-3125 4975)(-2950 4975);
WIRE 16 -1 (-2950 4925)(-2950 4875);
WIRE 16 -1 (-3125 4925)(-2950 4925);
WIRE 16 -1 (-2950 4875)(-2950 4825);
WIRE 16 -1 (-3125 4875)(-2950 4875);
WIRE 16 -1 (-2950 4825)(-2950 4775);
WIRE 16 -1 (-3125 4825)(-2950 4825);
WIRE 16 -1 (-2950 4775)(-2950 4725);
WIRE 16 -1 (-3125 4775)(-2950 4775);
WIRE 16 -1 (-2950 4725)(-2950 4675);
WIRE 16 -1 (-3125 4725)(-2950 4725);
WIRE 16 -1 (-2950 4675)(-2950 4625);
WIRE 16 -1 (-3125 4675)(-2950 4675);
WIRE 16 -1 (-2950 4625)(-2950 4575);
WIRE 16 -1 (-3125 4625)(-2950 4625);
WIRE 16 -1 (-2950 4575)(-2950 4525);
WIRE 16 -1 (-3125 4575)(-2950 4575);
WIRE 16 -1 (-2950 4525)(-2950 4475);
WIRE 16 -1 (-3125 4525)(-2950 4525);
WIRE 16 -1 (-2950 4475)(-2950 4425);
WIRE 16 -1 (-3125 4475)(-2950 4475);
WIRE 16 -1 (-2950 4425)(-2950 4375);
WIRE 16 -1 (-3125 4425)(-2950 4425);
WIRE 16 -1 (-2950 4375)(-2950 4325);
WIRE 16 -1 (-3125 4375)(-2950 4375);
WIRE 16 -1 (-2950 4325)(-2950 4275);
WIRE 16 -1 (-3125 4325)(-2950 4325);
WIRE 16 -1 (-2950 4275)(-2950 4225);
WIRE 16 -1 (-3125 4275)(-2950 4275);
WIRE 16 -1 (-2950 4225)(-2950 4175);
WIRE 16 -1 (-3125 4225)(-2950 4225);
WIRE 16 -1 (-2950 4175)(-2950 4125);
WIRE 16 -1 (-3125 4175)(-2950 4175);
WIRE 16 -1 (-3125 4125)(-2950 4125);
WIRE 16 -1 (-2950 4125)(-2950 4075);
WIRE 16 -1 (-2950 4075)(-2950 4025);
WIRE 16 -1 (-3125 4075)(-2950 4075);
WIRE 16 -1 (-2950 4025)(-2950 3975);
WIRE 16 -1 (-3125 4025)(-2950 4025);
WIRE 16 -1 (-2950 3975)(-2950 3925);
WIRE 16 -1 (-3125 3975)(-2950 3975);
WIRE 16 -1 (-2950 3925)(-2950 3875);
WIRE 16 -1 (-3125 3925)(-2950 3925);
WIRE 16 -1 (-2950 3875)(-2950 3825);
WIRE 16 -1 (-3125 3875)(-2950 3875);
WIRE 16 -1 (-2950 3825)(-2950 3775);
WIRE 16 -1 (-3125 3825)(-2950 3825);
WIRE 16 -1 (-2950 3775)(-2950 3725);
WIRE 16 -1 (-3125 3775)(-2950 3775);
WIRE 16 -1 (-2950 3725)(-2950 3675);
WIRE 16 -1 (-3125 3725)(-2950 3725);
WIRE 16 -1 (-2950 3675)(-2950 3625);
WIRE 16 -1 (-3125 3675)(-2950 3675);
WIRE 16 -1 (-2950 3625)(-2950 3575);
WIRE 16 -1 (-3125 3625)(-2950 3625);
WIRE 16 -1 (-2950 3575)(-2950 3525);
WIRE 16 -1 (-3125 3575)(-2950 3575);
WIRE 16 -1 (-2950 3525)(-2950 3475);
WIRE 16 -1 (-3125 3525)(-2950 3525);
WIRE 16 -1 (-2950 3475)(-2950 3425);
WIRE 16 -1 (-3125 3475)(-2950 3475);
WIRE 16 -1 (-2950 3425)(-2950 3375);
WIRE 16 -1 (-3125 3425)(-2950 3425);
WIRE 16 -1 (-2950 3375)(-2950 3325);
WIRE 16 -1 (-3125 3375)(-2950 3375);
WIRE 16 -1 (-2950 3325)(-2950 3275);
WIRE 16 -1 (-3125 3325)(-2950 3325);
WIRE 16 -1 (-2950 3275)(-2950 3225);
WIRE 16 -1 (-3125 3275)(-2950 3275);
WIRE 16 -1 (-2950 3225)(-2950 3175);
WIRE 16 -1 (-3125 3225)(-2950 3225);
WIRE 16 -1 (-2950 3175)(-2950 3125);
WIRE 16 -1 (-3125 3175)(-2950 3175);
WIRE 16 -1 (-2950 3125)(-2950 3075);
WIRE 16 -1 (-3125 3125)(-2950 3125);
WIRE 16 -1 (-2950 3075)(-2950 3025);
WIRE 16 -1 (-3125 3075)(-2950 3075);
WIRE 16 -1 (-2950 3025)(-2950 2975);
WIRE 16 -1 (-3125 3025)(-2950 3025);
WIRE 16 -1 (-2950 2975)(-2950 2925);
WIRE 16 -1 (-3125 2975)(-2950 2975);
WIRE 16 -1 (-2950 2925)(-2950 2875);
WIRE 16 -1 (-3125 2925)(-2950 2925);
WIRE 16 -1 (-2950 2875)(-2950 2825);
WIRE 16 -1 (-3125 2875)(-2950 2875);
WIRE 16 -1 (-2950 2825)(-2950 2775);
WIRE 16 -1 (-3125 2825)(-2950 2825);
WIRE 16 -1 (-2950 2775)(-2950 2725);
WIRE 16 -1 (-3125 2775)(-2950 2775);
WIRE 16 -1 (-2950 2725)(-2950 2675);
WIRE 16 -1 (-3125 2725)(-2950 2725);
WIRE 16 -1 (-2950 2675)(-2950 2625);
WIRE 16 -1 (-3125 2675)(-2950 2675);
WIRE 16 -1 (-2950 2625)(-2950 2575);
WIRE 16 -1 (-3125 2625)(-2950 2625);
WIRE 16 -1 (-2950 2575)(-2950 2525);
WIRE 16 -1 (-3125 2575)(-2950 2575);
WIRE 16 -1 (-2950 2525)(-2950 2475);
WIRE 16 -1 (-3125 2525)(-2950 2525);
WIRE 16 -1 (-2950 2475)(-2950 2425);
WIRE 16 -1 (-3125 2475)(-2950 2475);
WIRE 16 -1 (-2950 2425)(-2950 2375);
WIRE 16 -1 (-3125 2425)(-2950 2425);
WIRE 16 -1 (-2950 2375)(-2950 2325);
WIRE 16 -1 (-3125 2375)(-2950 2375);
WIRE 16 -1 (-2950 2325)(-2950 2275);
WIRE 16 -1 (-3125 2325)(-2950 2325);
WIRE 16 -1 (-2950 2275)(-2950 2225);
WIRE 16 -1 (-3125 2275)(-2950 2275);
WIRE 16 -1 (-2950 2225)(-2950 2175);
WIRE 16 -1 (-3125 2225)(-2950 2225);
WIRE 16 -1 (-2950 2175)(-2950 2125);
WIRE 16 -1 (-3125 2175)(-2950 2175);
WIRE 16 -1 (-2950 2125)(-2950 2075);
WIRE 16 -1 (-3125 2125)(-2950 2125);
WIRE 16 -1 (-3125 2075)(-2950 2075);
WIRE 16 -1 (-2950 2075)(-2950 2025);
WIRE 16 -1 (-2950 2025)(-2950 1975);
WIRE 16 -1 (-3125 2025)(-2950 2025);
WIRE 16 -1 (-2950 1975)(-2950 1925);
WIRE 16 -1 (-3125 1975)(-2950 1975);
WIRE 16 -1 (-2950 1925)(-2950 1875);
WIRE 16 -1 (-3125 1925)(-2950 1925);
WIRE 16 -1 (-2950 1875)(-2950 1825);
WIRE 16 -1 (-3125 1875)(-2950 1875);
WIRE 16 -1 (-2950 1825)(-2950 1775);
WIRE 16 -1 (-3125 1825)(-2950 1825);
WIRE 16 -1 (-2950 1775)(-2950 1725);
WIRE 16 -1 (-3125 1775)(-2950 1775);
WIRE 16 -1 (-2950 1725)(-2950 1675);
WIRE 16 -1 (-3125 1725)(-2950 1725);
WIRE 16 -1 (-2950 1675)(-2950 1625);
WIRE 16 -1 (-3125 1675)(-2950 1675);
WIRE 16 -1 (-2950 1625)(-2950 1575);
WIRE 16 -1 (-3125 1625)(-2950 1625);
WIRE 16 -1 (-2950 1575)(-2950 1525);
WIRE 16 -1 (-3125 1575)(-2950 1575);
WIRE 16 -1 (-2950 1525)(-2950 1475);
WIRE 16 -1 (-3125 1525)(-2950 1525);
WIRE 16 -1 (-2950 1475)(-2950 1425);
WIRE 16 -1 (-3125 1475)(-2950 1475);
WIRE 16 -1 (-2950 1425)(-2950 1375);
WIRE 16 -1 (-3125 1425)(-2950 1425);
WIRE 16 -1 (-2950 1375)(-2950 1325);
WIRE 16 -1 (-3125 1375)(-2950 1375);
WIRE 16 -1 (-2950 1325)(-2950 1275);
WIRE 16 -1 (-3125 1325)(-2950 1325);
WIRE 16 -1 (-2950 1275)(-2950 1225);
WIRE 16 -1 (-3125 1275)(-2950 1275);
WIRE 16 -1 (-2950 1225)(-2950 1175);
WIRE 16 -1 (-3125 1225)(-2950 1225);
WIRE 16 -1 (-2950 1175)(-2950 1125);
WIRE 16 -1 (-3125 1175)(-2950 1175);
WIRE 16 -1 (-2950 1125)(-2950 1075);
WIRE 16 -1 (-3125 1125)(-2950 1125);
WIRE 16 -1 (-2950 1075)(-2950 1025);
WIRE 16 -1 (-3125 1075)(-2950 1075);
WIRE 16 -1 (-2950 1025)(-2950 975);
WIRE 16 -1 (-3125 1025)(-2950 1025);
WIRE 16 -1 (-2950 975)(-2950 925);
WIRE 16 -1 (-3125 975)(-2950 975);
WIRE 16 -1 (-2950 925)(-2950 875);
WIRE 16 -1 (-3125 925)(-2950 925);
WIRE 16 -1 (-2950 875)(-2950 825);
WIRE 16 -1 (-3125 875)(-2950 875);
WIRE 16 -1 (-2950 825)(-2950 775);
WIRE 16 -1 (-3125 825)(-2950 825);
WIRE 16 -1 (-2950 775)(-2950 725);
WIRE 16 -1 (-3125 775)(-2950 775);
WIRE 16 -1 (-2950 725)(-2950 675);
WIRE 16 -1 (-3125 725)(-2950 725);
WIRE 16 -1 (-2950 675)(-2950 625);
WIRE 16 -1 (-3125 675)(-2950 675);
WIRE 16 -1 (-2950 625)(-2950 575);
WIRE 16 -1 (-3125 625)(-2950 625);
WIRE 16 -1 (-2950 450)(-2950 575);
WIRE 16 -1 (-3125 575)(-2950 575);
WIRE 16 -1 (-2325 6300)(-2150 6300);
WIRE 16 -1 (-2325 6300)(-2325 6250);
WIRE 16 -1 (-2150 6250)(-2325 6250);
WIRE 16 -1 (-2325 6250)(-2325 6200);
WIRE 16 -1 (-2325 6200)(-2150 6200);
WIRE 16 -1 (-2325 6200)(-2325 6150);
WIRE 16 -1 (-2325 6150)(-2150 6150);
WIRE 16 -1 (-2325 6150)(-2325 6100);
WIRE 16 -1 (-2325 6100)(-2150 6100);
WIRE 16 -1 (-2325 6100)(-2325 6050);
WIRE 16 -1 (-2325 6050)(-2150 6050);
WIRE 16 -1 (-2325 6050)(-2325 6000);
WIRE 16 -1 (-2150 6000)(-2325 6000);
WIRE 16 -1 (-2325 6000)(-2325 5950);
WIRE 16 -1 (-2325 5950)(-2150 5950);
WIRE 16 -1 (-2325 5950)(-2325 5900);
WIRE 16 -1 (-2325 5900)(-2150 5900);
WIRE 16 -1 (-2325 5900)(-2325 5850);
WIRE 16 -1 (-2325 5850)(-2150 5850);
WIRE 16 -1 (-2325 5850)(-2325 5800);
WIRE 16 -1 (-2325 5800)(-2150 5800);
WIRE 16 -1 (-2325 5800)(-2325 5750);
WIRE 16 -1 (-2150 5750)(-2325 5750);
WIRE 16 -1 (-2325 5750)(-2325 5700);
WIRE 16 -1 (-2325 5700)(-2150 5700);
WIRE 16 -1 (-2325 5700)(-2325 5650);
WIRE 16 -1 (-2325 5650)(-2150 5650);
WIRE 16 -1 (-2325 5650)(-2325 5600);
WIRE 16 -1 (-2325 5600)(-2150 5600);
WIRE 16 -1 (-2325 5600)(-2325 5550);
WIRE 16 -1 (-2325 5550)(-2150 5550);
WIRE 16 -1 (-2325 5550)(-2325 5500);
WIRE 16 -1 (-2150 5500)(-2325 5500);
WIRE 16 -1 (-2325 5500)(-2325 5450);
WIRE 16 -1 (-2325 5450)(-2150 5450);
WIRE 16 -1 (-2325 5450)(-2325 5400);
WIRE 16 -1 (-2325 5400)(-2150 5400);
WIRE 16 -1 (-2325 5400)(-2325 5350);
WIRE 16 -1 (-2325 5350)(-2150 5350);
WIRE 16 -1 (-2325 5350)(-2325 5300);
WIRE 16 -1 (-2325 5300)(-2150 5300);
WIRE 16 -1 (-2325 5300)(-2325 5250);
WIRE 16 -1 (-2150 5250)(-2325 5250);
WIRE 16 -1 (-2325 5250)(-2325 5200);
WIRE 16 -1 (-2325 5200)(-2150 5200);
WIRE 16 -1 (-2325 5200)(-2325 5150);
WIRE 16 -1 (-2325 5150)(-2150 5150);
WIRE 16 -1 (-2325 5150)(-2325 5100);
WIRE 16 -1 (-2325 5100)(-2150 5100);
WIRE 16 -1 (-2325 5100)(-2325 5050);
WIRE 16 -1 (-2325 5050)(-2150 5050);
WIRE 16 -1 (-2325 5050)(-2325 5000);
WIRE 16 -1 (-2150 5000)(-2325 5000);
WIRE 16 -1 (-2325 5000)(-2325 4950);
WIRE 16 -1 (-2325 4950)(-2150 4950);
WIRE 16 -1 (-2325 4950)(-2325 4900);
WIRE 16 -1 (-2325 4900)(-2150 4900);
WIRE 16 -1 (-2325 4900)(-2325 4850);
WIRE 16 -1 (-2325 4850)(-2150 4850);
WIRE 16 -1 (-2325 4850)(-2325 4800);
WIRE 16 -1 (-2325 4800)(-2150 4800);
WIRE 16 -1 (-2325 4800)(-2325 4750);
WIRE 16 -1 (-2150 4750)(-2325 4750);
WIRE 16 -1 (-2325 4750)(-2325 4700);
WIRE 16 -1 (-2325 4700)(-2150 4700);
WIRE 16 -1 (-2325 4700)(-2325 4650);
WIRE 16 -1 (-2325 4650)(-2150 4650);
WIRE 16 -1 (-2325 4650)(-2325 4600);
WIRE 16 -1 (-2325 4600)(-2150 4600);
WIRE 16 -1 (-2325 4600)(-2325 4550);
WIRE 16 -1 (-2325 4550)(-2150 4550);
WIRE 16 -1 (-2325 4550)(-2325 4500);
WIRE 16 -1 (-2150 4500)(-2325 4500);
WIRE 16 -1 (-2325 4500)(-2325 4450);
WIRE 16 -1 (-2325 4450)(-2150 4450);
WIRE 16 -1 (-2325 4450)(-2325 4400);
WIRE 16 -1 (-2325 4400)(-2150 4400);
WIRE 16 -1 (-2325 4400)(-2325 4350);
WIRE 16 -1 (-2325 4350)(-2150 4350);
WIRE 16 -1 (-2325 4350)(-2325 4300);
WIRE 16 -1 (-2325 4300)(-2150 4300);
WIRE 16 -1 (-2325 4300)(-2325 4250);
WIRE 16 -1 (-2150 4250)(-2325 4250);
WIRE 16 -1 (-2325 4250)(-2325 4200);
WIRE 16 -1 (-2325 4200)(-2150 4200);
WIRE 16 -1 (-2325 4200)(-2325 4150);
WIRE 16 -1 (-2325 4150)(-2150 4150);
WIRE 16 -1 (-2325 4150)(-2325 4100);
WIRE 16 -1 (-2325 4100)(-2150 4100);
WIRE 16 -1 (-2325 4100)(-2325 4050);
WIRE 16 -1 (-2325 4050)(-2150 4050);
WIRE 16 -1 (-2325 4050)(-2325 4000);
WIRE 16 -1 (-2325 4000)(-2150 4000);
WIRE 16 -1 (-2325 4000)(-2325 3950);
WIRE 16 -1 (-2150 3950)(-2325 3950);
WIRE 16 -1 (-2325 3950)(-2325 3900);
WIRE 16 -1 (-2325 3900)(-2150 3900);
WIRE 16 -1 (-2325 3900)(-2325 3850);
WIRE 16 -1 (-2325 3850)(-2150 3850);
WIRE 16 -1 (-2325 3850)(-2325 3800);
WIRE 16 -1 (-2325 3800)(-2150 3800);
WIRE 16 -1 (-2325 3800)(-2325 3750);
WIRE 16 -1 (-2325 3750)(-2150 3750);
WIRE 16 -1 (-2325 3750)(-2325 3700);
WIRE 16 -1 (-2150 3700)(-2325 3700);
WIRE 16 -1 (-2325 3700)(-2325 3650);
WIRE 16 -1 (-2325 3650)(-2150 3650);
WIRE 16 -1 (-2325 3650)(-2325 3600);
WIRE 16 -1 (-2325 3600)(-2150 3600);
WIRE 16 -1 (-2325 3600)(-2325 3550);
WIRE 16 -1 (-2325 3550)(-2150 3550);
WIRE 16 -1 (-2325 3550)(-2325 3500);
WIRE 16 -1 (-2325 3500)(-2150 3500);
WIRE 16 -1 (-2325 3500)(-2325 3450);
WIRE 16 -1 (-2150 3450)(-2325 3450);
WIRE 16 -1 (-2325 3450)(-2325 3400);
WIRE 16 -1 (-2325 3400)(-2150 3400);
WIRE 16 -1 (-2325 3400)(-2325 3350);
WIRE 16 -1 (-2325 3350)(-2150 3350);
WIRE 16 -1 (-2325 3350)(-2325 3300);
WIRE 16 -1 (-2325 3300)(-2150 3300);
WIRE 16 -1 (-2325 3300)(-2325 3250);
WIRE 16 -1 (-2325 3250)(-2150 3250);
WIRE 16 -1 (-2325 3250)(-2325 3200);
WIRE 16 -1 (-2150 3200)(-2325 3200);
WIRE 16 -1 (-2325 3200)(-2325 3150);
WIRE 16 -1 (-2325 3150)(-2150 3150);
WIRE 16 -1 (-2325 3150)(-2325 3100);
WIRE 16 -1 (-2325 3100)(-2150 3100);
WIRE 16 -1 (-2325 3100)(-2325 3050);
WIRE 16 -1 (-2325 3050)(-2150 3050);
WIRE 16 -1 (-2325 3050)(-2325 3000);
WIRE 16 -1 (-2325 3000)(-2150 3000);
WIRE 16 -1 (-2325 3000)(-2325 2950);
WIRE 16 -1 (-2150 2950)(-2325 2950);
WIRE 16 -1 (-2325 2950)(-2325 2900);
WIRE 16 -1 (-2325 2900)(-2150 2900);
WIRE 16 -1 (-2325 2900)(-2325 2850);
WIRE 16 -1 (-2325 2850)(-2150 2850);
WIRE 16 -1 (-2325 2850)(-2325 2800);
WIRE 16 -1 (-2325 2800)(-2150 2800);
WIRE 16 -1 (-2325 2800)(-2325 2750);
WIRE 16 -1 (-2325 2750)(-2150 2750);
WIRE 16 -1 (-2325 2750)(-2325 2700);
WIRE 16 -1 (-2150 2700)(-2325 2700);
WIRE 16 -1 (-2325 2700)(-2325 2650);
WIRE 16 -1 (-2325 2650)(-2150 2650);
WIRE 16 -1 (-2325 2650)(-2325 2600);
WIRE 16 -1 (-2325 2600)(-2150 2600);
WIRE 16 -1 (-2325 2600)(-2325 2550);
WIRE 16 -1 (-2325 2550)(-2150 2550);
WIRE 16 -1 (-2325 2550)(-2325 2500);
WIRE 16 -1 (-2325 2500)(-2150 2500);
WIRE 16 -1 (-2325 2500)(-2325 2450);
WIRE 16 -1 (-2150 2450)(-2325 2450);
WIRE 16 -1 (-2325 2450)(-2325 2400);
WIRE 16 -1 (-2325 2400)(-2150 2400);
WIRE 16 -1 (-2325 2400)(-2325 2350);
WIRE 16 -1 (-2325 2350)(-2150 2350);
WIRE 16 -1 (-2325 2350)(-2325 2300);
WIRE 16 -1 (-2325 2300)(-2150 2300);
WIRE 16 -1 (-2325 2300)(-2325 2250);
WIRE 16 -1 (-2325 2250)(-2150 2250);
WIRE 16 -1 (-2325 2250)(-2325 2200);
WIRE 16 -1 (-2150 2200)(-2325 2200);
WIRE 16 -1 (-2325 2200)(-2325 2150);
WIRE 16 -1 (-2325 2150)(-2150 2150);
WIRE 16 -1 (-2325 2150)(-2325 2100);
WIRE 16 -1 (-2325 2100)(-2150 2100);
WIRE 16 -1 (-2325 2100)(-2325 2050);
WIRE 16 -1 (-2325 2050)(-2150 2050);
WIRE 16 -1 (-2325 2050)(-2325 2000);
WIRE 16 -1 (-2325 2000)(-2150 2000);
WIRE 16 -1 (-2325 2000)(-2325 1950);
WIRE 16 -1 (-2325 1950)(-2150 1950);
WIRE 16 -1 (-2325 1950)(-2325 1900);
WIRE 16 -1 (-2150 1900)(-2325 1900);
WIRE 16 -1 (-2325 1900)(-2325 1850);
WIRE 16 -1 (-2325 1850)(-2150 1850);
WIRE 16 -1 (-2325 1850)(-2325 1800);
WIRE 16 -1 (-2325 1800)(-2150 1800);
WIRE 16 -1 (-2325 1800)(-2325 1750);
WIRE 16 -1 (-2325 1750)(-2150 1750);
WIRE 16 -1 (-2325 1750)(-2325 1700);
WIRE 16 -1 (-2325 1700)(-2150 1700);
WIRE 16 -1 (-2325 1700)(-2325 1650);
WIRE 16 -1 (-2150 1650)(-2325 1650);
WIRE 16 -1 (-2325 1650)(-2325 1600);
WIRE 16 -1 (-2325 1600)(-2150 1600);
WIRE 16 -1 (-2325 1600)(-2325 1550);
WIRE 16 -1 (-2325 1550)(-2150 1550);
WIRE 16 -1 (-2325 1550)(-2325 1500);
WIRE 16 -1 (-2325 1500)(-2150 1500);
WIRE 16 -1 (-2325 1500)(-2325 1450);
WIRE 16 -1 (-2325 1450)(-2150 1450);
WIRE 16 -1 (-2325 1450)(-2325 1400);
WIRE 16 -1 (-2150 1400)(-2325 1400);
WIRE 16 -1 (-2325 1400)(-2325 1350);
WIRE 16 -1 (-2325 1350)(-2150 1350);
WIRE 16 -1 (-2325 1350)(-2325 1300);
WIRE 16 -1 (-2325 1300)(-2150 1300);
WIRE 16 -1 (-2325 1300)(-2325 1250);
WIRE 16 -1 (-2325 1250)(-2150 1250);
WIRE 16 -1 (-2325 1250)(-2325 1200);
WIRE 16 -1 (-2325 1200)(-2150 1200);
WIRE 16 -1 (-2325 1200)(-2325 1150);
WIRE 16 -1 (-2150 1150)(-2325 1150);
WIRE 16 -1 (-2325 1150)(-2325 1100);
WIRE 16 -1 (-2325 1100)(-2150 1100);
WIRE 16 -1 (-2325 1100)(-2325 1050);
WIRE 16 -1 (-2325 1050)(-2150 1050);
WIRE 16 -1 (-2325 1050)(-2325 1000);
WIRE 16 -1 (-2325 1000)(-2150 1000);
WIRE 16 -1 (-2325 1000)(-2325 950);
WIRE 16 -1 (-2325 950)(-2150 950);
WIRE 16 -1 (-2325 950)(-2325 900);
WIRE 16 -1 (-2150 900)(-2325 900);
WIRE 16 -1 (-2325 900)(-2325 850);
WIRE 16 -1 (-2325 850)(-2150 850);
WIRE 16 -1 (-2325 850)(-2325 800);
WIRE 16 -1 (-2325 800)(-2150 800);
WIRE 16 -1 (-2325 800)(-2325 750);
WIRE 16 -1 (-2325 750)(-2150 750);
WIRE 16 -1 (-2325 750)(-2325 700);
WIRE 16 -1 (-2325 700)(-2150 700);
WIRE 16 -1 (-2325 700)(-2325 650);
WIRE 16 -1 (-2150 650)(-2325 650);
WIRE 16 -1 (-2325 650)(-2325 600);
WIRE 16 -1 (-2325 600)(-2150 600);
WIRE 16 -1 (-2325 600)(-2325 550);
WIRE 16 -1 (-2150 550)(-2325 550);
WIRE 16 -1 (-2325 550)(-2325 500);
WIRE 16 -1 (-2150 500)(-2325 500);
WIRE 16 -1 (-2325 500)(-2325 450);
WIRE 16 -1 (-1050 6300)(-875 6300);
WIRE 16 -1 (-875 6300)(-875 6250);
WIRE 16 -1 (-875 6250)(-875 6200);
WIRE 16 -1 (-1050 6250)(-875 6250);
WIRE 16 -1 (-875 6200)(-875 6150);
WIRE 16 -1 (-1050 6200)(-875 6200);
WIRE 16 -1 (-1050 6150)(-875 6150);
WIRE 16 -1 (-875 6150)(-875 6100);
WIRE 16 -1 (-875 6100)(-875 6050);
WIRE 16 -1 (-1050 6100)(-875 6100);
WIRE 16 -1 (-875 6050)(-875 6000);
WIRE 16 -1 (-1050 6050)(-875 6050);
WIRE 16 -1 (-875 6000)(-875 5950);
WIRE 16 -1 (-1050 6000)(-875 6000);
WIRE 16 -1 (-875 5950)(-875 5900);
WIRE 16 -1 (-1050 5950)(-875 5950);
WIRE 16 -1 (-875 5900)(-875 5850);
WIRE 16 -1 (-1050 5900)(-875 5900);
WIRE 16 -1 (-875 5850)(-875 5800);
WIRE 16 -1 (-1050 5850)(-875 5850);
WIRE 16 -1 (-875 5800)(-875 5750);
WIRE 16 -1 (-1050 5800)(-875 5800);
WIRE 16 -1 (-875 5750)(-875 5700);
WIRE 16 -1 (-1050 5750)(-875 5750);
WIRE 16 -1 (-875 5700)(-875 5650);
WIRE 16 -1 (-1050 5700)(-875 5700);
WIRE 16 -1 (-875 5650)(-875 5600);
WIRE 16 -1 (-1050 5650)(-875 5650);
WIRE 16 -1 (-875 5600)(-875 5550);
WIRE 16 -1 (-1050 5600)(-875 5600);
WIRE 16 -1 (-875 5550)(-875 5500);
WIRE 16 -1 (-1050 5550)(-875 5550);
WIRE 16 -1 (-875 5500)(-875 5450);
WIRE 16 -1 (-1050 5500)(-875 5500);
WIRE 16 -1 (-875 5450)(-875 5400);
WIRE 16 -1 (-1050 5450)(-875 5450);
WIRE 16 -1 (-875 5400)(-875 5350);
WIRE 16 -1 (-1050 5400)(-875 5400);
WIRE 16 -1 (-875 5350)(-875 5300);
WIRE 16 -1 (-1050 5350)(-875 5350);
WIRE 16 -1 (-875 5300)(-875 5250);
WIRE 16 -1 (-1050 5300)(-875 5300);
WIRE 16 -1 (-875 5250)(-875 5200);
WIRE 16 -1 (-1050 5250)(-875 5250);
WIRE 16 -1 (-875 5200)(-875 5150);
WIRE 16 -1 (-1050 5200)(-875 5200);
WIRE 16 -1 (-875 5150)(-875 5100);
WIRE 16 -1 (-1050 5150)(-875 5150);
WIRE 16 -1 (-875 5100)(-875 5050);
WIRE 16 -1 (-1050 5100)(-875 5100);
WIRE 16 -1 (-875 5050)(-875 5000);
WIRE 16 -1 (-1050 5050)(-875 5050);
WIRE 16 -1 (-875 5000)(-875 4950);
WIRE 16 -1 (-1050 5000)(-875 5000);
WIRE 16 -1 (-875 4950)(-875 4900);
WIRE 16 -1 (-1050 4950)(-875 4950);
WIRE 16 -1 (-875 4900)(-875 4850);
WIRE 16 -1 (-1050 4900)(-875 4900);
WIRE 16 -1 (-875 4850)(-875 4800);
WIRE 16 -1 (-1050 4850)(-875 4850);
WIRE 16 -1 (-875 4800)(-875 4750);
WIRE 16 -1 (-1050 4800)(-875 4800);
WIRE 16 -1 (-875 4750)(-875 4700);
WIRE 16 -1 (-1050 4750)(-875 4750);
WIRE 16 -1 (-875 4700)(-875 4650);
WIRE 16 -1 (-1050 4700)(-875 4700);
WIRE 16 -1 (-875 4650)(-875 4600);
WIRE 16 -1 (-1050 4650)(-875 4650);
WIRE 16 -1 (-875 4600)(-875 4550);
WIRE 16 -1 (-1050 4600)(-875 4600);
WIRE 16 -1 (-875 4550)(-875 4500);
WIRE 16 -1 (-1050 4550)(-875 4550);
WIRE 16 -1 (-875 4500)(-875 4450);
WIRE 16 -1 (-1050 4500)(-875 4500);
WIRE 16 -1 (-875 4450)(-875 4400);
WIRE 16 -1 (-1050 4450)(-875 4450);
WIRE 16 -1 (-875 4400)(-875 4350);
WIRE 16 -1 (-1050 4400)(-875 4400);
WIRE 16 -1 (-875 4350)(-875 4300);
WIRE 16 -1 (-1050 4350)(-875 4350);
WIRE 16 -1 (-875 4300)(-875 4250);
WIRE 16 -1 (-1050 4300)(-875 4300);
WIRE 16 -1 (-875 4250)(-875 4200);
WIRE 16 -1 (-1050 4250)(-875 4250);
WIRE 16 -1 (-875 4200)(-875 4150);
WIRE 16 -1 (-1050 4200)(-875 4200);
WIRE 16 -1 (-875 4150)(-875 4100);
WIRE 16 -1 (-1050 4150)(-875 4150);
WIRE 16 -1 (-1050 4100)(-875 4100);
WIRE 16 -1 (-875 4100)(-875 4050);
WIRE 16 -1 (-875 4050)(-875 4000);
WIRE 16 -1 (-1050 4050)(-875 4050);
WIRE 16 -1 (-875 4000)(-875 3950);
WIRE 16 -1 (-1050 4000)(-875 4000);
WIRE 16 -1 (-875 3950)(-875 3900);
WIRE 16 -1 (-1050 3950)(-875 3950);
WIRE 16 -1 (-875 3900)(-875 3850);
WIRE 16 -1 (-1050 3900)(-875 3900);
WIRE 16 -1 (-875 3850)(-875 3800);
WIRE 16 -1 (-1050 3850)(-875 3850);
WIRE 16 -1 (-875 3800)(-875 3750);
WIRE 16 -1 (-1050 3800)(-875 3800);
WIRE 16 -1 (-875 3750)(-875 3700);
WIRE 16 -1 (-1050 3750)(-875 3750);
WIRE 16 -1 (-875 3700)(-875 3650);
WIRE 16 -1 (-1050 3700)(-875 3700);
WIRE 16 -1 (-875 3650)(-875 3600);
WIRE 16 -1 (-1050 3650)(-875 3650);
WIRE 16 -1 (-875 3600)(-875 3550);
WIRE 16 -1 (-1050 3600)(-875 3600);
WIRE 16 -1 (-875 3550)(-875 3500);
WIRE 16 -1 (-1050 3550)(-875 3550);
WIRE 16 -1 (-875 3500)(-875 3450);
WIRE 16 -1 (-1050 3500)(-875 3500);
WIRE 16 -1 (-875 3450)(-875 3400);
WIRE 16 -1 (-1050 3450)(-875 3450);
WIRE 16 -1 (-875 3400)(-875 3350);
WIRE 16 -1 (-1050 3400)(-875 3400);
WIRE 16 -1 (-875 3350)(-875 3300);
WIRE 16 -1 (-1050 3350)(-875 3350);
WIRE 16 -1 (-875 3300)(-875 3250);
WIRE 16 -1 (-1050 3300)(-875 3300);
WIRE 16 -1 (-875 3250)(-875 3200);
WIRE 16 -1 (-1050 3250)(-875 3250);
WIRE 16 -1 (-875 3200)(-875 3150);
WIRE 16 -1 (-1050 3200)(-875 3200);
WIRE 16 -1 (-875 3150)(-875 3100);
WIRE 16 -1 (-1050 3150)(-875 3150);
WIRE 16 -1 (-875 3100)(-875 3050);
WIRE 16 -1 (-1050 3100)(-875 3100);
WIRE 16 -1 (-875 3050)(-875 3000);
WIRE 16 -1 (-1050 3050)(-875 3050);
WIRE 16 -1 (-875 3000)(-875 2950);
WIRE 16 -1 (-1050 3000)(-875 3000);
WIRE 16 -1 (-875 2950)(-875 2900);
WIRE 16 -1 (-1050 2950)(-875 2950);
WIRE 16 -1 (-875 2900)(-875 2850);
WIRE 16 -1 (-1050 2900)(-875 2900);
WIRE 16 -1 (-875 2850)(-875 2800);
WIRE 16 -1 (-1050 2850)(-875 2850);
WIRE 16 -1 (-875 2800)(-875 2750);
WIRE 16 -1 (-1050 2800)(-875 2800);
WIRE 16 -1 (-875 2750)(-875 2700);
WIRE 16 -1 (-1050 2750)(-875 2750);
WIRE 16 -1 (-875 2700)(-875 2650);
WIRE 16 -1 (-1050 2700)(-875 2700);
WIRE 16 -1 (-875 2650)(-875 2600);
WIRE 16 -1 (-1050 2650)(-875 2650);
WIRE 16 -1 (-875 2600)(-875 2550);
WIRE 16 -1 (-1050 2600)(-875 2600);
WIRE 16 -1 (-875 2550)(-875 2500);
WIRE 16 -1 (-1050 2550)(-875 2550);
WIRE 16 -1 (-875 2500)(-875 2450);
WIRE 16 -1 (-1050 2500)(-875 2500);
WIRE 16 -1 (-875 2450)(-875 2400);
WIRE 16 -1 (-1050 2450)(-875 2450);
WIRE 16 -1 (-875 2400)(-875 2350);
WIRE 16 -1 (-1050 2400)(-875 2400);
WIRE 16 -1 (-875 2350)(-875 2300);
WIRE 16 -1 (-1050 2350)(-875 2350);
WIRE 16 -1 (-875 2300)(-875 2250);
WIRE 16 -1 (-1050 2300)(-875 2300);
WIRE 16 -1 (-875 2250)(-875 2200);
WIRE 16 -1 (-1050 2250)(-875 2250);
WIRE 16 -1 (-875 2200)(-875 2150);
WIRE 16 -1 (-1050 2200)(-875 2200);
WIRE 16 -1 (-875 2150)(-875 2100);
WIRE 16 -1 (-1050 2150)(-875 2150);
WIRE 16 -1 (-875 2100)(-875 2050);
WIRE 16 -1 (-1050 2100)(-875 2100);
WIRE 16 -1 (-1050 2050)(-875 2050);
WIRE 16 -1 (-875 2050)(-875 2000);
WIRE 16 -1 (-875 2000)(-875 1950);
WIRE 16 -1 (-1050 2000)(-875 2000);
WIRE 16 -1 (-875 1950)(-875 1900);
WIRE 16 -1 (-1050 1950)(-875 1950);
WIRE 16 -1 (-875 1900)(-875 1850);
WIRE 16 -1 (-1050 1900)(-875 1900);
WIRE 16 -1 (-875 1850)(-875 1800);
WIRE 16 -1 (-1050 1850)(-875 1850);
WIRE 16 -1 (-875 1800)(-875 1750);
WIRE 16 -1 (-1050 1800)(-875 1800);
WIRE 16 -1 (-875 1750)(-875 1700);
WIRE 16 -1 (-1050 1750)(-875 1750);
WIRE 16 -1 (-875 1700)(-875 1650);
WIRE 16 -1 (-1050 1700)(-875 1700);
WIRE 16 -1 (-875 1650)(-875 1600);
WIRE 16 -1 (-1050 1650)(-875 1650);
WIRE 16 -1 (-875 1600)(-875 1550);
WIRE 16 -1 (-1050 1600)(-875 1600);
WIRE 16 -1 (-875 1550)(-875 1500);
WIRE 16 -1 (-1050 1550)(-875 1550);
WIRE 16 -1 (-875 1500)(-875 1450);
WIRE 16 -1 (-1050 1500)(-875 1500);
WIRE 16 -1 (-875 1450)(-875 1400);
WIRE 16 -1 (-1050 1450)(-875 1450);
WIRE 16 -1 (-875 1400)(-875 1350);
WIRE 16 -1 (-1050 1400)(-875 1400);
WIRE 16 -1 (-875 1350)(-875 1300);
WIRE 16 -1 (-1050 1350)(-875 1350);
WIRE 16 -1 (-875 1300)(-875 1250);
WIRE 16 -1 (-1050 1300)(-875 1300);
WIRE 16 -1 (-875 1250)(-875 1200);
WIRE 16 -1 (-1050 1250)(-875 1250);
WIRE 16 -1 (-875 1200)(-875 1150);
WIRE 16 -1 (-1050 1200)(-875 1200);
WIRE 16 -1 (-875 1150)(-875 1100);
WIRE 16 -1 (-1050 1150)(-875 1150);
WIRE 16 -1 (-875 1100)(-875 1050);
WIRE 16 -1 (-1050 1100)(-875 1100);
WIRE 16 -1 (-875 1050)(-875 1000);
WIRE 16 -1 (-1050 1050)(-875 1050);
WIRE 16 -1 (-875 1000)(-875 950);
WIRE 16 -1 (-1050 1000)(-875 1000);
WIRE 16 -1 (-875 950)(-875 900);
WIRE 16 -1 (-1050 950)(-875 950);
WIRE 16 -1 (-875 900)(-875 850);
WIRE 16 -1 (-1050 900)(-875 900);
WIRE 16 -1 (-875 850)(-875 800);
WIRE 16 -1 (-1050 850)(-875 850);
WIRE 16 -1 (-875 800)(-875 750);
WIRE 16 -1 (-1050 800)(-875 800);
WIRE 16 -1 (-875 750)(-875 700);
WIRE 16 -1 (-1050 750)(-875 750);
WIRE 16 -1 (-875 700)(-875 650);
WIRE 16 -1 (-1050 700)(-875 700);
WIRE 16 -1 (-875 650)(-875 600);
WIRE 16 -1 (-1050 650)(-875 650);
WIRE 16 -1 (-875 600)(-875 550);
WIRE 16 -1 (-1050 600)(-875 600);
WIRE 16 -1 (-875 550)(-875 500);
WIRE 16 -1 (-1050 550)(-875 550);
WIRE 16 -1 (-875 450)(-875 500);
WIRE 16 -1 (-1050 500)(-875 500);
DOT 1 (-6475 3500);
DOT 1 (-8500 4900);
DOT 1 (-6475 4150);
DOT 1 (-7050 5750);
DOT 1 (-7050 5700);
DOT 1 (-6475 6150);
DOT 1 (-5025 6250);
DOT 1 (-4400 5975);
DOT 1 (-2950 6075);
DOT 1 (-2325 6100);
DOT 1 (-5025 5600);
DOT 1 (-8500 500);
DOT 1 (-8500 550);
DOT 1 (-8500 600);
DOT 1 (-8500 650);
DOT 1 (-8500 700);
DOT 1 (-8500 750);
DOT 1 (-8500 800);
DOT 1 (-8500 850);
DOT 1 (-8500 900);
DOT 1 (-8500 950);
DOT 1 (-8500 1000);
DOT 1 (-8500 1050);
DOT 1 (-8500 1100);
DOT 1 (-8500 1150);
DOT 1 (-8500 1200);
DOT 1 (-8500 1250);
DOT 1 (-8500 1300);
DOT 1 (-8500 1350);
DOT 1 (-8500 1400);
DOT 1 (-8500 1450);
DOT 1 (-8500 1500);
DOT 1 (-8500 1550);
DOT 1 (-8500 1650);
DOT 1 (-8500 1750);
DOT 1 (-8500 1700);
DOT 1 (-8500 1800);
DOT 1 (-8500 1850);
DOT 1 (-8500 1900);
DOT 1 (-8500 1950);
DOT 1 (-8500 2000);
DOT 1 (-8500 2050);
DOT 1 (-8500 2100);
DOT 1 (-8500 2150);
DOT 1 (-8500 2200);
DOT 1 (-8500 2250);
DOT 1 (-8500 2300);
DOT 1 (-8500 2350);
DOT 1 (-8500 2400);
DOT 1 (-8500 2450);
DOT 1 (-8500 2500);
DOT 1 (-8500 2550);
DOT 1 (-8500 2600);
DOT 1 (-8500 2650);
DOT 1 (-8500 2700);
DOT 1 (-8500 2750);
DOT 1 (-8500 2800);
DOT 1 (-8500 2850);
DOT 1 (-8500 2900);
DOT 1 (-8500 2950);
DOT 1 (-8500 3000);
DOT 1 (-8500 3050);
DOT 1 (-8500 3100);
DOT 1 (-8500 3200);
DOT 1 (-8500 3150);
DOT 1 (-8500 3250);
DOT 1 (-8500 3300);
DOT 1 (-8500 3350);
DOT 1 (-8500 3400);
DOT 1 (-8500 3450);
DOT 1 (-8500 3550);
DOT 1 (-8500 3500);
DOT 1 (-8500 3600);
DOT 1 (-8500 3650);
DOT 1 (-8500 3700);
DOT 1 (-8500 3750);
DOT 1 (-8500 3800);
DOT 1 (-8500 3850);
DOT 1 (-8500 3900);
DOT 1 (-8500 3950);
DOT 1 (-8500 4000);
DOT 1 (-8500 4050);
DOT 1 (-8500 4100);
DOT 1 (-8500 4150);
DOT 1 (-8500 4200);
DOT 1 (-8500 4250);
DOT 1 (-8500 4300);
DOT 1 (-8500 4350);
DOT 1 (-8500 4400);
DOT 1 (-8500 4450);
DOT 1 (-8500 4500);
DOT 1 (-8500 4550);
DOT 1 (-8500 4600);
DOT 1 (-8500 4650);
DOT 1 (-8500 4700);
DOT 1 (-8500 4750);
DOT 1 (-8500 4800);
DOT 1 (-8500 4850);
DOT 1 (-8500 4950);
DOT 1 (-8500 5000);
DOT 1 (-8500 5050);
DOT 1 (-8500 5100);
DOT 1 (-8500 5150);
DOT 1 (-8500 5200);
DOT 1 (-8500 5250);
DOT 1 (-8500 5300);
DOT 1 (-8500 5350);
DOT 1 (-8500 5400);
DOT 1 (-8500 5450);
DOT 1 (-8500 5500);
DOT 1 (-8500 5550);
DOT 1 (-8500 5600);
DOT 1 (-8500 5650);
DOT 1 (-8500 5700);
DOT 1 (-8500 5750);
DOT 1 (-8500 5800);
DOT 1 (-8500 5850);
DOT 1 (-8500 5900);
DOT 1 (-8500 5950);
DOT 1 (-8500 6000);
DOT 1 (-8500 6050);
DOT 1 (-8500 6100);
DOT 1 (-8500 6150);
DOT 1 (-8500 6200);
DOT 1 (-8500 6250);
DOT 1 (-8500 6300);
DOT 1 (-8500 6350);
DOT 1 (-7050 600);
DOT 1 (-7050 550);
DOT 1 (-7050 650);
DOT 1 (-7050 750);
DOT 1 (-7050 700);
DOT 1 (-7050 850);
DOT 1 (-7050 800);
DOT 1 (-7050 900);
DOT 1 (-7050 1000);
DOT 1 (-7050 950);
DOT 1 (-6475 500);
DOT 1 (-6475 550);
DOT 1 (-6475 600);
DOT 1 (-6475 650);
DOT 1 (-6475 700);
DOT 1 (-6475 750);
DOT 1 (-6475 800);
DOT 1 (-6475 850);
DOT 1 (-6475 900);
DOT 1 (-6475 1000);
DOT 1 (-6475 950);
DOT 1 (-7050 1050);
DOT 1 (-7050 1100);
DOT 1 (-7050 1150);
DOT 1 (-7050 1200);
DOT 1 (-7050 1250);
DOT 1 (-7050 1350);
DOT 1 (-7050 1400);
DOT 1 (-7050 1300);
DOT 1 (-7050 1450);
DOT 1 (-7050 1500);
DOT 1 (-7050 1550);
DOT 1 (-7050 1600);
DOT 1 (-7050 1650);
DOT 1 (-7050 1700);
DOT 1 (-7050 1750);
DOT 1 (-7050 1800);
DOT 1 (-7050 1900);
DOT 1 (-7050 1850);
DOT 1 (-7050 1950);
DOT 1 (-7050 2000);
DOT 1 (-6475 1050);
DOT 1 (-6475 1100);
DOT 1 (-6475 1150);
DOT 1 (-6475 1200);
DOT 1 (-6475 1250);
DOT 1 (-6475 1300);
DOT 1 (-6475 1350);
DOT 1 (-6475 1400);
DOT 1 (-6475 1450);
DOT 1 (-6475 1500);
DOT 1 (-6475 1550);
DOT 1 (-6475 1600);
DOT 1 (-6475 1650);
DOT 1 (-6475 1700);
DOT 1 (-6475 1750);
DOT 1 (-6475 1800);
DOT 1 (-6475 1850);
DOT 1 (-6475 1900);
DOT 1 (-6475 1950);
DOT 1 (-6475 2000);
DOT 1 (-7050 2050);
DOT 1 (-6475 2050);
DOT 1 (-7050 2150);
DOT 1 (-7050 2100);
DOT 1 (-7050 2300);
DOT 1 (-7050 2250);
DOT 1 (-7050 2200);
DOT 1 (-7050 2400);
DOT 1 (-7050 2350);
DOT 1 (-7050 2550);
DOT 1 (-7050 2500);
DOT 1 (-7050 2450);
DOT 1 (-7050 2650);
DOT 1 (-7050 2600);
DOT 1 (-7050 2700);
DOT 1 (-7050 2800);
DOT 1 (-7050 2750);
DOT 1 (-7050 2900);
DOT 1 (-7050 2850);
DOT 1 (-7050 2950);
DOT 1 (-7050 3050);
DOT 1 (-7050 3000);
DOT 1 (-6475 2100);
DOT 1 (-6475 2150);
DOT 1 (-6475 2200);
DOT 1 (-6475 2250);
DOT 1 (-6475 2300);
DOT 1 (-6475 2350);
DOT 1 (-6475 2400);
DOT 1 (-6475 2500);
DOT 1 (-6475 2450);
DOT 1 (-6475 2550);
DOT 1 (-6475 2600);
DOT 1 (-6475 2650);
DOT 1 (-6475 2700);
DOT 1 (-6475 2750);
DOT 1 (-6475 2800);
DOT 1 (-6475 2850);
DOT 1 (-6475 2900);
DOT 1 (-6475 2950);
DOT 1 (-6475 3050);
DOT 1 (-6475 3000);
DOT 1 (-7050 3100);
DOT 1 (-7050 3150);
DOT 1 (-7050 3200);
DOT 1 (-7050 3250);
DOT 1 (-7050 3300);
DOT 1 (-7050 3400);
DOT 1 (-7050 3450);
DOT 1 (-7050 3350);
DOT 1 (-7050 3500);
DOT 1 (-7050 3550);
DOT 1 (-7050 3650);
DOT 1 (-7050 3700);
DOT 1 (-7050 3600);
DOT 1 (-7050 3750);
DOT 1 (-7050 3800);
DOT 1 (-7050 3850);
DOT 1 (-7050 3950);
DOT 1 (-7050 3900);
DOT 1 (-7050 4000);
DOT 1 (-7050 4050);
DOT 1 (-6475 3100);
DOT 1 (-6475 3150);
DOT 1 (-6475 3200);
DOT 1 (-6475 3250);
DOT 1 (-6475 3300);
DOT 1 (-6475 3350);
DOT 1 (-6475 3400);
DOT 1 (-6475 3450);
DOT 1 (-6475 3550);
DOT 1 (-6475 3600);
DOT 1 (-6475 3650);
DOT 1 (-6475 3700);
DOT 1 (-6475 3750);
DOT 1 (-6475 3800);
DOT 1 (-6475 3850);
DOT 1 (-6475 3900);
DOT 1 (-6475 3950);
DOT 1 (-6475 4000);
DOT 1 (-6475 4050);
DOT 1 (-5025 500);
DOT 1 (-5025 600);
DOT 1 (-5025 550);
DOT 1 (-5025 650);
DOT 1 (-5025 700);
DOT 1 (-5025 750);
DOT 1 (-5025 800);
DOT 1 (-5025 850);
DOT 1 (-5025 900);
DOT 1 (-5025 950);
DOT 1 (-5025 1000);
DOT 1 (-4400 625);
DOT 1 (-4400 575);
DOT 1 (-4400 675);
DOT 1 (-4400 725);
DOT 1 (-4400 775);
DOT 1 (-4400 825);
DOT 1 (-4400 875);
DOT 1 (-4400 925);
DOT 1 (-4400 975);
DOT 1 (-4400 1025);
DOT 1 (-5025 1050);
DOT 1 (-5025 1100);
DOT 1 (-5025 1150);
DOT 1 (-5025 1200);
DOT 1 (-5025 1250);
DOT 1 (-5025 1300);
DOT 1 (-5025 1350);
DOT 1 (-5025 1400);
DOT 1 (-5025 1450);
DOT 1 (-5025 1500);
DOT 1 (-5025 1550);
DOT 1 (-5025 1600);
DOT 1 (-5025 1650);
DOT 1 (-5025 1700);
DOT 1 (-5025 1750);
DOT 1 (-5025 1800);
DOT 1 (-5025 1850);
DOT 1 (-5025 1900);
DOT 1 (-5025 1950);
DOT 1 (-5025 2000);
DOT 1 (-4400 1075);
DOT 1 (-4400 1125);
DOT 1 (-4400 1175);
DOT 1 (-4400 1225);
DOT 1 (-4400 1275);
DOT 1 (-4400 1325);
DOT 1 (-4400 1375);
DOT 1 (-4400 1425);
DOT 1 (-4400 1475);
DOT 1 (-4400 1525);
DOT 1 (-4400 1575);
DOT 1 (-4400 1625);
DOT 1 (-4400 1675);
DOT 1 (-4400 1725);
DOT 1 (-4400 1775);
DOT 1 (-4400 1875);
DOT 1 (-4400 1825);
DOT 1 (-4400 1925);
DOT 1 (-4400 1975);
DOT 1 (-4400 2025);
DOT 1 (-5025 2050);
DOT 1 (-5025 2100);
DOT 1 (-5025 2150);
DOT 1 (-5025 2200);
DOT 1 (-5025 2250);
DOT 1 (-5025 2300);
DOT 1 (-5025 2350);
DOT 1 (-5025 2400);
DOT 1 (-5025 2450);
DOT 1 (-5025 2500);
DOT 1 (-5025 2550);
DOT 1 (-5025 2600);
DOT 1 (-5025 2650);
DOT 1 (-5025 2700);
DOT 1 (-5025 2750);
DOT 1 (-5025 2800);
DOT 1 (-5025 2850);
DOT 1 (-5025 2900);
DOT 1 (-5025 2950);
DOT 1 (-5025 3000);
DOT 1 (-5025 3050);
DOT 1 (-4400 2075);
DOT 1 (-4400 2125);
DOT 1 (-4400 2175);
DOT 1 (-4400 2225);
DOT 1 (-4400 2275);
DOT 1 (-4400 2325);
DOT 1 (-4400 2375);
DOT 1 (-4400 2425);
DOT 1 (-4400 2475);
DOT 1 (-4400 2525);
DOT 1 (-4400 2575);
DOT 1 (-4400 2625);
DOT 1 (-4400 2675);
DOT 1 (-4400 2725);
DOT 1 (-4400 2775);
DOT 1 (-4400 2825);
DOT 1 (-4400 2875);
DOT 1 (-4400 2925);
DOT 1 (-4400 2975);
DOT 1 (-4400 3025);
DOT 1 (-4400 3075);
DOT 1 (-5025 3100);
DOT 1 (-5025 3200);
DOT 1 (-5025 3150);
DOT 1 (-5025 3300);
DOT 1 (-5025 3250);
DOT 1 (-5025 3350);
DOT 1 (-5025 3400);
DOT 1 (-5025 3450);
DOT 1 (-5025 3550);
DOT 1 (-5025 3500);
DOT 1 (-5025 3600);
DOT 1 (-5025 3650);
DOT 1 (-5025 3700);
DOT 1 (-5025 3750);
DOT 1 (-5025 3800);
DOT 1 (-5025 3850);
DOT 1 (-5025 3900);
DOT 1 (-5025 3950);
DOT 1 (-5025 4050);
DOT 1 (-5025 4000);
DOT 1 (-4400 3125);
DOT 1 (-4400 3175);
DOT 1 (-4400 3225);
DOT 1 (-4400 3275);
DOT 1 (-4400 3325);
DOT 1 (-4400 3375);
DOT 1 (-4400 3425);
DOT 1 (-4400 3475);
DOT 1 (-4400 3525);
DOT 1 (-4400 3575);
DOT 1 (-4400 3625);
DOT 1 (-4400 3675);
DOT 1 (-4400 3725);
DOT 1 (-4400 3775);
DOT 1 (-4400 3825);
DOT 1 (-4400 3875);
DOT 1 (-4400 3925);
DOT 1 (-4400 3975);
DOT 1 (-4400 4025);
DOT 1 (-4400 4075);
DOT 1 (-7050 4100);
DOT 1 (-6475 4100);
DOT 1 (-5025 4100);
DOT 1 (-7050 4200);
DOT 1 (-7050 4150);
DOT 1 (-7050 4300);
DOT 1 (-7050 4350);
DOT 1 (-7050 4250);
DOT 1 (-7050 4450);
DOT 1 (-7050 4400);
DOT 1 (-7050 4550);
DOT 1 (-7050 4600);
DOT 1 (-7050 4500);
DOT 1 (-7050 4650);
DOT 1 (-7050 4700);
DOT 1 (-7050 4750);
DOT 1 (-7050 4800);
DOT 1 (-7050 4850);
DOT 1 (-7050 4950);
DOT 1 (-7050 4900);
DOT 1 (-7050 5000);
DOT 1 (-7050 5100);
DOT 1 (-7050 5050);
DOT 1 (-6475 4200);
DOT 1 (-6475 4250);
DOT 1 (-6475 4300);
DOT 1 (-6475 4350);
DOT 1 (-6475 4400);
DOT 1 (-6475 4450);
DOT 1 (-6475 4550);
DOT 1 (-6475 4500);
DOT 1 (-6475 4600);
DOT 1 (-6475 4650);
DOT 1 (-6475 4700);
DOT 1 (-6475 4750);
DOT 1 (-6475 4800);
DOT 1 (-6475 4850);
DOT 1 (-6475 4900);
DOT 1 (-6475 4950);
DOT 1 (-6475 5000);
DOT 1 (-6475 5100);
DOT 1 (-6475 5050);
DOT 1 (-7050 5200);
DOT 1 (-7050 5150);
DOT 1 (-7050 5250);
DOT 1 (-7050 5350);
DOT 1 (-7050 5300);
DOT 1 (-7050 5450);
DOT 1 (-7050 5500);
DOT 1 (-7050 5400);
DOT 1 (-7050 5550);
DOT 1 (-7050 5600);
DOT 1 (-7050 5650);
DOT 1 (-7050 5800);
DOT 1 (-7050 5850);
DOT 1 (-7050 5900);
DOT 1 (-7050 6000);
DOT 1 (-7050 5950);
DOT 1 (-7050 6050);
DOT 1 (-7050 6100);
DOT 1 (-6475 5150);
DOT 1 (-6475 5200);
DOT 1 (-6475 5250);
DOT 1 (-6475 5300);
DOT 1 (-6475 5350);
DOT 1 (-6475 5400);
DOT 1 (-6475 5450);
DOT 1 (-6475 5500);
DOT 1 (-6475 5550);
DOT 1 (-6475 5600);
DOT 1 (-6475 5650);
DOT 1 (-6475 5700);
DOT 1 (-6475 5750);
DOT 1 (-6475 5800);
DOT 1 (-6475 5850);
DOT 1 (-6475 5900);
DOT 1 (-6475 5950);
DOT 1 (-6475 6000);
DOT 1 (-6475 6050);
DOT 1 (-6475 6100);
DOT 1 (-7050 6150);
DOT 1 (-7050 6250);
DOT 1 (-7050 6200);
DOT 1 (-7050 6350);
DOT 1 (-7050 6300);
DOT 1 (-6475 6250);
DOT 1 (-6475 6200);
DOT 1 (-6475 6300);
DOT 1 (-5025 4150);
DOT 1 (-5025 4200);
DOT 1 (-5025 4250);
DOT 1 (-5025 4300);
DOT 1 (-5025 4350);
DOT 1 (-5025 4450);
DOT 1 (-5025 4400);
DOT 1 (-5025 4500);
DOT 1 (-5025 4550);
DOT 1 (-5025 4600);
DOT 1 (-5025 4650);
DOT 1 (-5025 4700);
DOT 1 (-5025 4750);
DOT 1 (-5025 4800);
DOT 1 (-5025 4850);
DOT 1 (-5025 4900);
DOT 1 (-5025 4950);
DOT 1 (-5025 5000);
DOT 1 (-5025 5050);
DOT 1 (-5025 5100);
DOT 1 (-4400 4125);
DOT 1 (-4400 4175);
DOT 1 (-4400 4225);
DOT 1 (-4400 4275);
DOT 1 (-4400 4325);
DOT 1 (-4400 4375);
DOT 1 (-4400 4425);
DOT 1 (-4400 4475);
DOT 1 (-4400 4575);
DOT 1 (-4400 4525);
DOT 1 (-4400 4625);
DOT 1 (-4400 4675);
DOT 1 (-4400 4725);
DOT 1 (-4400 4775);
DOT 1 (-4400 4825);
DOT 1 (-4400 4875);
DOT 1 (-4400 4925);
DOT 1 (-4400 4975);
DOT 1 (-4400 5025);
DOT 1 (-4400 5075);
DOT 1 (-4400 5125);
DOT 1 (-5025 5150);
DOT 1 (-5025 5200);
DOT 1 (-5025 5250);
DOT 1 (-5025 5300);
DOT 1 (-5025 5350);
DOT 1 (-5025 5400);
DOT 1 (-5025 5450);
DOT 1 (-5025 5500);
DOT 1 (-5025 5550);
DOT 1 (-5025 5650);
DOT 1 (-5025 5700);
DOT 1 (-5025 5750);
DOT 1 (-5025 5800);
DOT 1 (-5025 5850);
DOT 1 (-5025 5900);
DOT 1 (-5025 5950);
DOT 1 (-5025 6000);
DOT 1 (-5025 6050);
DOT 1 (-5025 6100);
DOT 1 (-4400 5175);
DOT 1 (-4400 5225);
DOT 1 (-4400 5275);
DOT 1 (-4400 5325);
DOT 1 (-4400 5375);
DOT 1 (-4400 5425);
DOT 1 (-4400 5475);
DOT 1 (-4400 5525);
DOT 1 (-4400 5575);
DOT 1 (-4400 5625);
DOT 1 (-4400 5675);
DOT 1 (-4400 5725);
DOT 1 (-4400 5775);
DOT 1 (-4400 5825);
DOT 1 (-4400 5875);
DOT 1 (-4400 5925);
DOT 1 (-4400 6025);
DOT 1 (-4400 6075);
DOT 1 (-4400 6125);
DOT 1 (-5025 6150);
DOT 1 (-5025 6200);
DOT 1 (-4400 6175);
DOT 1 (-4400 6225);
DOT 1 (-2950 575);
DOT 1 (-2950 625);
DOT 1 (-2950 725);
DOT 1 (-2950 675);
DOT 1 (-2950 775);
DOT 1 (-2950 875);
DOT 1 (-2950 825);
DOT 1 (-2950 975);
DOT 1 (-2950 925);
DOT 1 (-2325 500);
DOT 1 (-2325 550);
DOT 1 (-2325 600);
DOT 1 (-2325 650);
DOT 1 (-2325 700);
DOT 1 (-2325 750);
DOT 1 (-2325 800);
DOT 1 (-2325 850);
DOT 1 (-2325 900);
DOT 1 (-2325 950);
DOT 1 (-2325 1000);
DOT 1 (-2950 1025);
DOT 1 (-2950 1125);
DOT 1 (-2950 1075);
DOT 1 (-2950 1275);
DOT 1 (-2950 1225);
DOT 1 (-2950 1175);
DOT 1 (-2950 1375);
DOT 1 (-2950 1325);
DOT 1 (-2950 1525);
DOT 1 (-2950 1475);
DOT 1 (-2950 1425);
DOT 1 (-2950 1575);
DOT 1 (-2950 1625);
DOT 1 (-2950 1675);
DOT 1 (-2950 1775);
DOT 1 (-2950 1725);
DOT 1 (-2950 1875);
DOT 1 (-2950 1825);
DOT 1 (-2950 1925);
DOT 1 (-2950 2025);
DOT 1 (-2950 1975);
DOT 1 (-2325 1050);
DOT 1 (-2325 1100);
DOT 1 (-2325 1150);
DOT 1 (-2325 1200);
DOT 1 (-2325 1250);
DOT 1 (-2325 1300);
DOT 1 (-2325 1350);
DOT 1 (-2325 1400);
DOT 1 (-2325 1450);
DOT 1 (-2325 1500);
DOT 1 (-2325 1550);
DOT 1 (-2325 1600);
DOT 1 (-2325 1650);
DOT 1 (-2325 1700);
DOT 1 (-2325 1750);
DOT 1 (-2325 1800);
DOT 1 (-2325 1850);
DOT 1 (-2325 1900);
DOT 1 (-2325 1950);
DOT 1 (-2325 2000);
DOT 1 (-2325 2050);
DOT 1 (-2950 2175);
DOT 1 (-2950 2125);
DOT 1 (-2950 2075);
DOT 1 (-2950 2275);
DOT 1 (-2950 2225);
DOT 1 (-2950 2375);
DOT 1 (-2950 2425);
DOT 1 (-2950 2325);
DOT 1 (-2950 2525);
DOT 1 (-2950 2475);
DOT 1 (-2950 2625);
DOT 1 (-2950 2675);
DOT 1 (-2950 2575);
DOT 1 (-2950 2725);
DOT 1 (-2950 2775);
DOT 1 (-2950 2825);
DOT 1 (-2950 2925);
DOT 1 (-2950 2875);
DOT 1 (-2950 2975);
DOT 1 (-2950 3025);
DOT 1 (-2325 2100);
DOT 1 (-2325 2150);
DOT 1 (-2325 2200);
DOT 1 (-2325 2250);
DOT 1 (-2325 2300);
DOT 1 (-2325 2350);
DOT 1 (-2325 2400);
DOT 1 (-2325 2450);
DOT 1 (-2325 2500);
DOT 1 (-2325 2550);
DOT 1 (-2325 2650);
DOT 1 (-2325 2600);
DOT 1 (-2325 2700);
DOT 1 (-2325 2750);
DOT 1 (-2325 2800);
DOT 1 (-2325 2850);
DOT 1 (-2325 2900);
DOT 1 (-2325 2950);
DOT 1 (-2325 3000);
DOT 1 (-2325 3050);
DOT 1 (-2950 3075);
DOT 1 (-2950 3175);
DOT 1 (-2950 3125);
DOT 1 (-2950 3325);
DOT 1 (-2950 3275);
DOT 1 (-2950 3225);
DOT 1 (-2950 3375);
DOT 1 (-2950 3425);
DOT 1 (-2950 3575);
DOT 1 (-2950 3525);
DOT 1 (-2950 3475);
DOT 1 (-2950 3625);
DOT 1 (-2950 3675);
DOT 1 (-2950 3725);
DOT 1 (-2950 3825);
DOT 1 (-2950 3775);
DOT 1 (-2950 3925);
DOT 1 (-2950 3875);
DOT 1 (-2950 3975);
DOT 1 (-2950 4075);
DOT 1 (-2950 4025);
DOT 1 (-2325 3100);
DOT 1 (-2325 3150);
DOT 1 (-2325 3200);
DOT 1 (-2325 3250);
DOT 1 (-2325 3300);
DOT 1 (-2325 3350);
DOT 1 (-2325 3400);
DOT 1 (-2325 3450);
DOT 1 (-2325 3500);
DOT 1 (-2325 3550);
DOT 1 (-2325 3600);
DOT 1 (-2325 3650);
DOT 1 (-2325 3700);
DOT 1 (-2325 3750);
DOT 1 (-2325 3800);
DOT 1 (-2325 3850);
DOT 1 (-2325 3900);
DOT 1 (-2325 3950);
DOT 1 (-2325 4000);
DOT 1 (-2325 4050);
DOT 1 (-875 500);
DOT 1 (-875 600);
DOT 1 (-875 550);
DOT 1 (-875 650);
DOT 1 (-875 700);
DOT 1 (-875 750);
DOT 1 (-875 850);
DOT 1 (-875 800);
DOT 1 (-875 900);
DOT 1 (-875 950);
DOT 1 (-875 1000);
DOT 1 (-875 1050);
DOT 1 (-875 1100);
DOT 1 (-875 1150);
DOT 1 (-875 1250);
DOT 1 (-875 1200);
DOT 1 (-875 1300);
DOT 1 (-875 1350);
DOT 1 (-875 1400);
DOT 1 (-875 1500);
DOT 1 (-875 1450);
DOT 1 (-875 1600);
DOT 1 (-875 1550);
DOT 1 (-875 1650);
DOT 1 (-875 1750);
DOT 1 (-875 1700);
DOT 1 (-875 1800);
DOT 1 (-875 1850);
DOT 1 (-875 1900);
DOT 1 (-875 2000);
DOT 1 (-875 1950);
DOT 1 (-875 2050);
DOT 1 (-875 2100);
DOT 1 (-875 2150);
DOT 1 (-875 2200);
DOT 1 (-875 2250);
DOT 1 (-875 2300);
DOT 1 (-875 2400);
DOT 1 (-875 2350);
DOT 1 (-875 2450);
DOT 1 (-875 2500);
DOT 1 (-875 2550);
DOT 1 (-875 2650);
DOT 1 (-875 2600);
DOT 1 (-875 2700);
DOT 1 (-875 2750);
DOT 1 (-875 2800);
DOT 1 (-875 2900);
DOT 1 (-875 2850);
DOT 1 (-875 2950);
DOT 1 (-875 3000);
DOT 1 (-875 3050);
DOT 1 (-875 3100);
DOT 1 (-875 3150);
DOT 1 (-875 3200);
DOT 1 (-875 3250);
DOT 1 (-875 3300);
DOT 1 (-875 3350);
DOT 1 (-875 3400);
DOT 1 (-875 3450);
DOT 1 (-875 3500);
DOT 1 (-875 3550);
DOT 1 (-875 3600);
DOT 1 (-875 3650);
DOT 1 (-875 3700);
DOT 1 (-875 3800);
DOT 1 (-875 3750);
DOT 1 (-875 3850);
DOT 1 (-875 3900);
DOT 1 (-875 3950);
DOT 1 (-875 4050);
DOT 1 (-875 4000);
DOT 1 (-2325 4100);
DOT 1 (-875 4100);
DOT 1 (-2950 4175);
DOT 1 (-2950 4125);
DOT 1 (-2950 4225);
DOT 1 (-2950 4325);
DOT 1 (-2950 4275);
DOT 1 (-2950 4475);
DOT 1 (-2950 4425);
DOT 1 (-2950 4375);
DOT 1 (-2950 4525);
DOT 1 (-2950 4575);
DOT 1 (-2950 4675);
DOT 1 (-2950 4725);
DOT 1 (-2950 4625);
DOT 1 (-2950 4825);
DOT 1 (-2950 4775);
DOT 1 (-2950 4875);
DOT 1 (-2950 4975);
DOT 1 (-2950 4925);
DOT 1 (-2950 5025);
DOT 1 (-2950 5075);
DOT 1 (-2325 4150);
DOT 1 (-2325 4200);
DOT 1 (-2325 4250);
DOT 1 (-2325 4300);
DOT 1 (-2325 4350);
DOT 1 (-2325 4400);
DOT 1 (-2325 4450);
DOT 1 (-2325 4500);
DOT 1 (-2325 4550);
DOT 1 (-2325 4600);
DOT 1 (-2325 4700);
DOT 1 (-2325 4650);
DOT 1 (-2325 4750);
DOT 1 (-2325 4800);
DOT 1 (-2325 4850);
DOT 1 (-2325 4900);
DOT 1 (-2325 4950);
DOT 1 (-2325 5000);
DOT 1 (-2325 5050);
DOT 1 (-2325 5100);
DOT 1 (-2950 5125);
DOT 1 (-2950 5225);
DOT 1 (-2950 5175);
DOT 1 (-2950 5375);
DOT 1 (-2950 5325);
DOT 1 (-2950 5275);
DOT 1 (-2950 5425);
DOT 1 (-2950 5475);
DOT 1 (-2950 5625);
DOT 1 (-2950 5575);
DOT 1 (-2950 5525);
DOT 1 (-2950 5675);
DOT 1 (-2950 5725);
DOT 1 (-2950 5875);
DOT 1 (-2950 5825);
DOT 1 (-2950 5775);
DOT 1 (-2950 5975);
DOT 1 (-2950 5925);
DOT 1 (-2950 6025);
DOT 1 (-2950 6125);
DOT 1 (-2325 5200);
DOT 1 (-2325 5150);
DOT 1 (-2325 5250);
DOT 1 (-2325 5300);
DOT 1 (-2325 5350);
DOT 1 (-2325 5400);
DOT 1 (-2325 5450);
DOT 1 (-2325 5500);
DOT 1 (-2325 5550);
DOT 1 (-2325 5600);
DOT 1 (-2325 5650);
DOT 1 (-2325 5700);
DOT 1 (-2325 5750);
DOT 1 (-2325 5800);
DOT 1 (-2325 5850);
DOT 1 (-2325 5900);
DOT 1 (-2325 5950);
DOT 1 (-2325 6000);
DOT 1 (-2325 6050);
DOT 1 (-2325 6150);
DOT 1 (-2950 6175);
DOT 1 (-2950 6225);
DOT 1 (-2950 6275);
DOT 1 (-2950 6325);
DOT 1 (-2325 6200);
DOT 1 (-2325 6250);
DOT 1 (-875 4150);
DOT 1 (-875 4200);
DOT 1 (-875 4250);
DOT 1 (-875 4300);
DOT 1 (-875 4350);
DOT 1 (-875 4400);
DOT 1 (-875 4450);
DOT 1 (-875 4500);
DOT 1 (-875 4550);
DOT 1 (-875 4600);
DOT 1 (-875 4700);
DOT 1 (-875 4650);
DOT 1 (-875 4800);
DOT 1 (-875 4750);
DOT 1 (-875 4850);
DOT 1 (-875 4950);
DOT 1 (-875 4900);
DOT 1 (-875 5000);
DOT 1 (-875 5050);
DOT 1 (-875 5100);
DOT 1 (-875 5200);
DOT 1 (-875 5150);
DOT 1 (-875 5250);
DOT 1 (-875 5300);
DOT 1 (-875 5350);
DOT 1 (-875 5400);
DOT 1 (-875 5450);
DOT 1 (-875 5500);
DOT 1 (-875 5550);
DOT 1 (-875 5600);
DOT 1 (-875 5650);
DOT 1 (-875 5700);
DOT 1 (-875 5750);
DOT 1 (-875 5850);
DOT 1 (-875 5800);
DOT 1 (-875 5900);
DOT 1 (-875 5950);
DOT 1 (-875 6000);
DOT 1 (-875 6100);
DOT 1 (-875 6050);
DOT 1 (-875 6150);
DOT 1 (-875 6200);
DOT 1 (-875 6250);
DOT 1 (-8500 1600);
QUIT
